FILE_TYPE = MACRO_DRAWING;
SET COLOR_WIRE YELLOW;
SET COLOR_PROP MONO;
SET COLOR_DOT WHITE;
SET COLOR_ARC YELLOW;
SET COLOR_BODY GREEN;
SET COLOR_NOTE MONO;
SET PROP_DISPLAY VALUE;
SET PAGE_NUMBER P244;
FORCEADD TAP..7
(-5925 1475);
FORCEPROP 3 LASTPIN (-5925 1525) SIG_NAME P3E_CPU0_PE1_PCH_CON_TXP<15>
J 0
(-5915 1535);
DISPLAY 0.659574 (-5915 1535);
PAINT MONO (-5915 1535);
DISPLAY INVISIBLE (-5915 1535);
FORCEPROP 1 LASTPIN (-5925 1525) BN 15
R 1
J 0
(-5932 1473);
DISPLAY 0.680851 (-5932 1473);
PAINT GREEN (-5932 1473);
FORCEPROP 1 LAST PATH I1
J 0
(-5927 1475);
DISPLAY 0.872340 (-5927 1475);
PAINT GREEN (-5927 1475);
DISPLAY INVISIBLE (-5927 1475);
FORCEPROP 2 LAST CDS_LIB mstr_standard
J 0
(-5925 1475);
PAINT MONO (-5925 1475);
DISPLAY INVISIBLE (-5925 1475);
FORCEPROP 1 LAST BODY_TYPE PLUMBING
J 0
(-5875 1475);
DISPLAY 2.276596 (-5875 1475);
PAINT GREEN (-5875 1475);
DISPLAY INVISIBLE (-5875 1475);
FORCEPROP 1 LAST HDL_TAP TRUE
J 0
(-5605 1345);
DISPLAY 2.276596 (-5605 1345);
PAINT GREEN (-5605 1345);
DISPLAY INVISIBLE (-5605 1345);
FORCEADD OFFPAGE..1
(-6200 3625);
FORCEPROP 2 LAST $XR1 105 
J 0
(-6541 3625);
DISPLAY 0.638298 (-6541 3625);
PAINT MONO (-6541 3625);
FORCEPROP 2 LAST $XR0 30 
J 0
(-6421 3625);
DISPLAY 0.638298 (-6421 3625);
PAINT MONO (-6421 3625);
FORCEPROP 2 LAST PATH I10
J 0
(-6400 3675);
DISPLAY 1.021277 (-6400 3675);
PAINT ORANGE (-6400 3675);
DISPLAY INVISIBLE (-6400 3675);
FORCEPROP 2 LAST CDS_LIB mstr_standard
J 0
(-6200 3625);
PAINT MONO (-6200 3625);
DISPLAY INVISIBLE (-6200 3625);
FORCEPROP 1 LAST OFFPAGE TRUE
J 0
(-5880 3495);
PAINT GREEN (-5880 3495);
DISPLAY INVISIBLE (-5880 3495);
FORCEPROP 1 LAST COMMENT_BODY TRUE
J 0
(-6080 3525);
DISPLAY 2.276596 (-6080 3525);
PAINT GREEN (-6080 3525);
DISPLAY INVISIBLE (-6080 3525);
FORCEADD TAP..3
(-2500 3575);
FORCEPROP 3 LASTPIN (-2500 3525) SIG_NAME P3E_CPU0_PE1_PCH_RXN<10>
J 0
(-2490 3535);
DISPLAY 0.659574 (-2490 3535);
PAINT MONO (-2490 3535);
DISPLAY INVISIBLE (-2490 3535);
FORCEPROP 1 LASTPIN (-2500 3525) BN 10
R 1
J 0
(-2507 3513);
DISPLAY 0.680851 (-2507 3513);
PAINT GREEN (-2507 3513);
FORCEPROP 1 LAST PATH I100
J 0
(-2502 3575);
DISPLAY 0.872340 (-2502 3575);
PAINT GREEN (-2502 3575);
DISPLAY INVISIBLE (-2502 3575);
FORCEPROP 2 LAST CDS_LIB mstr_standard
J 0
(-2500 3575);
PAINT MONO (-2500 3575);
DISPLAY INVISIBLE (-2500 3575);
FORCEPROP 1 LAST BODY_TYPE PLUMBING
J 0
(-2450 3525);
DISPLAY 2.276596 (-2450 3525);
PAINT GREEN (-2450 3525);
DISPLAY INVISIBLE (-2450 3525);
FORCEPROP 1 LAST HDL_TAP TRUE
J 0
(-2180 3445);
DISPLAY 2.276596 (-2180 3445);
PAINT GREEN (-2180 3445);
DISPLAY INVISIBLE (-2180 3445);
FORCEADD TAP..3
(-2300 3575);
FORCEPROP 3 LASTPIN (-2300 3525) SIG_NAME P3E_CPU0_PE1_PCH_RXN<9>
J 0
(-2290 3535);
DISPLAY 0.659574 (-2290 3535);
PAINT MONO (-2290 3535);
DISPLAY INVISIBLE (-2290 3535);
FORCEPROP 1 LASTPIN (-2300 3525) BN 9
R 1
J 0
(-2307 3513);
DISPLAY 0.680851 (-2307 3513);
PAINT GREEN (-2307 3513);
FORCEPROP 1 LAST PATH I101
J 0
(-2302 3575);
DISPLAY 0.872340 (-2302 3575);
PAINT GREEN (-2302 3575);
DISPLAY INVISIBLE (-2302 3575);
FORCEPROP 2 LAST CDS_LIB mstr_standard
J 0
(-2300 3575);
PAINT MONO (-2300 3575);
DISPLAY INVISIBLE (-2300 3575);
FORCEPROP 1 LAST BODY_TYPE PLUMBING
J 0
(-2250 3525);
DISPLAY 2.276596 (-2250 3525);
PAINT GREEN (-2250 3525);
DISPLAY INVISIBLE (-2250 3525);
FORCEPROP 1 LAST HDL_TAP TRUE
J 0
(-1980 3445);
DISPLAY 2.276596 (-1980 3445);
PAINT GREEN (-1980 3445);
DISPLAY INVISIBLE (-1980 3445);
FORCEADD TAP..3
(-2100 3575);
FORCEPROP 3 LASTPIN (-2100 3525) SIG_NAME P3E_CPU0_PE1_PCH_RXN<8>
J 0
(-2090 3535);
DISPLAY 0.659574 (-2090 3535);
PAINT MONO (-2090 3535);
DISPLAY INVISIBLE (-2090 3535);
FORCEPROP 1 LASTPIN (-2100 3525) BN 8
R 1
J 0
(-2107 3513);
DISPLAY 0.680851 (-2107 3513);
PAINT GREEN (-2107 3513);
FORCEPROP 1 LAST PATH I102
J 0
(-2102 3575);
DISPLAY 0.872340 (-2102 3575);
PAINT GREEN (-2102 3575);
DISPLAY INVISIBLE (-2102 3575);
FORCEPROP 2 LAST CDS_LIB mstr_standard
J 0
(-2100 3575);
PAINT MONO (-2100 3575);
DISPLAY INVISIBLE (-2100 3575);
FORCEPROP 1 LAST BODY_TYPE PLUMBING
J 0
(-2050 3525);
DISPLAY 2.276596 (-2050 3525);
PAINT GREEN (-2050 3525);
DISPLAY INVISIBLE (-2050 3525);
FORCEPROP 1 LAST HDL_TAP TRUE
J 0
(-1780 3445);
DISPLAY 2.276596 (-1780 3445);
PAINT GREEN (-1780 3445);
DISPLAY INVISIBLE (-1780 3445);
FORCEADD RES..2
(-2025 2075);
FORCEPROP 1 LAST MATERIAL CHIP
J 0
(-1985 2000);
DISPLAY 0.617021 (-1985 2000);
PAINT SKYBLUE (-1985 2000);
FORCEPROP 1 LASTPIN (-2025 1975) $PN 2
J 0
(-2020 1985);
DISPLAY 0.787234 (-2020 1985);
PAINT ORANGE (-2020 1985);
FORCEPROP 1 LAST PACK_TYPE 0402
J 0
(-1960 1900);
DISPLAY 0.617021 (-1960 1900);
PAINT SKYBLUE (-1960 1900);
FORCEPROP 1 LAST PART_NUMBER G21497-005
J 0
(-1985 1950);
DISPLAY 0.617021 (-1985 1950);
PAINT BLUE (-1985 1950);
FORCEPROP 1 LAST WATTAGE 1/16W
J 0
(-1985 2050);
DISPLAY 0.617021 (-1985 2050);
PAINT SKYBLUE (-1985 2050);
FORCEPROP 1 LAST TOLERANCE 5%
J 0
(-1980 2100);
DISPLAY 0.617021 (-1980 2100);
PAINT SKYBLUE (-1980 2100);
FORCEPROP 1 LAST VALUE 0.0
J 0
(-1980 2150);
DISPLAY 0.617021 (-1980 2150);
PAINT SKYBLUE (-1980 2150);
FORCEPROP 1 LASTPIN (-2025 2175) $PN 1
J 0
(-2020 2137);
DISPLAY 0.787234 (-2020 2137);
PAINT ORANGE (-2020 2137);
FORCEPROP 1 LAST $LOCATION R785
J 0
(-1980 2200);
DISPLAY 0.617021 (-1980 2200);
PAINT AQUA (-1980 2200);
FORCEPROP 0 LAST GROUP PCIE_RISER
J 0
(-1982 2253);
DISPLAY 0.638298 (-1982 2253);
PAINT BROWN (-1982 2253);
DISPLAY BOTH (-1982 2253);
FORCEPROP 1 LAST PATH I103
J 0
(-1975 2250);
DISPLAY 0.978723 (-1975 2250);
PAINT WHITE (-1975 2250);
DISPLAY INVISIBLE (-1975 2250);
FORCEPROP 0 LAST CDS_LOCATION R785
J 0
(-1975 2250);
PAINT MONO (-1975 2250);
DISPLAY INVISIBLE (-1975 2250);
FORCEPROP 2 LAST CDS_LIB mstr_discrete
J 0
(-2025 2075);
PAINT MONO (-2025 2075);
DISPLAY INVISIBLE (-2025 2075);
FORCEPROP 2 LAST ROOM PCIE_STEERING
J 0
(-1975 2250);
PAINT MONO (-1975 2250);
DISPLAY INVISIBLE (-1975 2250);
FORCEPROP 0 LAST SEC 1
J 0
(-1975 2250);
PAINT MONO (-1975 2250);
DISPLAY INVISIBLE (-1975 2250);
FORCEPROP 2 LAST SEC_TYPE 0402
J 0
(-1975 2300);
DISPLAY 1.021277 (-1975 2300);
PAINT ORANGE (-1975 2300);
DISPLAY INVISIBLE (-1975 2300);
FORCEADD OFFPAGE..2
(-1800 2725);
FORCEPROP 2 LAST $XR0 108 
J 0
(-1611 2725);
DISPLAY 0.638298 (-1611 2725);
PAINT MONO (-1611 2725);
FORCEPROP 2 LAST PATH I104
J 0
(-1475 2775);
DISPLAY 1.021277 (-1475 2775);
PAINT ORANGE (-1475 2775);
DISPLAY INVISIBLE (-1475 2775);
FORCEPROP 2 LAST CDS_LIB mstr_standard
J 0
(-1800 2725);
PAINT MONO (-1800 2725);
DISPLAY INVISIBLE (-1800 2725);
FORCEPROP 1 LAST OFFPAGE TRUE
J 0
(-1475 2600);
DISPLAY 0.872340 (-1475 2600);
PAINT GREEN (-1475 2600);
DISPLAY INVISIBLE (-1475 2600);
FORCEPROP 1 LAST COMMENT_BODY TRUE
J 0
(-1845 2630);
DISPLAY 0.872340 (-1845 2630);
PAINT GREEN (-1845 2630);
DISPLAY INVISIBLE (-1845 2630);
FORCEADD TAP..3
(-5925 2275);
FORCEPROP 3 LASTPIN (-5925 2225) SIG_NAME P3E_CPU0_PE1_PCH_TXP<15>
J 0
(-5915 2235);
DISPLAY 0.659574 (-5915 2235);
PAINT MONO (-5915 2235);
DISPLAY INVISIBLE (-5915 2235);
FORCEPROP 1 LASTPIN (-5925 2225) BN 15
R 1
J 0
(-5932 2213);
DISPLAY 0.680851 (-5932 2213);
PAINT GREEN (-5932 2213);
FORCEPROP 1 LAST PATH I11
J 0
(-5927 2275);
DISPLAY 0.872340 (-5927 2275);
PAINT GREEN (-5927 2275);
DISPLAY INVISIBLE (-5927 2275);
FORCEPROP 2 LAST CDS_LIB mstr_standard
J 0
(-5925 2275);
PAINT MONO (-5925 2275);
DISPLAY INVISIBLE (-5925 2275);
FORCEPROP 1 LAST BODY_TYPE PLUMBING
J 0
(-5875 2225);
DISPLAY 2.276596 (-5875 2225);
PAINT GREEN (-5875 2225);
DISPLAY INVISIBLE (-5875 2225);
FORCEPROP 1 LAST HDL_TAP TRUE
J 0
(-5605 2145);
DISPLAY 2.276596 (-5605 2145);
PAINT GREEN (-5605 2145);
DISPLAY INVISIBLE (-5605 2145);
FORCEADD CAP..1
R 2
(-5725 2025);
FORCEPROP 1 LAST $LOCATION C827
J 2
(-5775 2125);
DISPLAY 0.617021 (-5775 2125);
PAINT AQUA (-5775 2125);
FORCEPROP 1 LAST VOLTAGE 16V
J 2
(-5775 2025);
DISPLAY 0.617021 (-5775 2025);
PAINT SKYBLUE (-5775 2025);
FORCEPROP 1 LAST PART_NUMBER A36096-155
J 2
(-5775 1875);
DISPLAY 0.617021 (-5775 1875);
PAINT BLUE (-5775 1875);
FORCEPROP 1 LAST PACK_TYPE 0402
J 2
(-5775 1825);
DISPLAY 0.617021 (-5775 1825);
PAINT SKYBLUE (-5775 1825);
FORCEPROP 1 LASTPIN (-5725 2125) $PN 1
J 2
(-5735 2105);
DISPLAY 0.787234 (-5735 2105);
PAINT ORANGE (-5735 2105);
FORCEPROP 1 LASTPIN (-5725 1925) $PN 2
J 2
(-5735 1905);
DISPLAY 0.787234 (-5735 1905);
PAINT ORANGE (-5735 1905);
FORCEPROP 1 LAST VALUE 0.22UF
J 2
(-5775 2075);
DISPLAY 0.617021 (-5775 2075);
PAINT SKYBLUE (-5775 2075);
FORCEPROP 1 LAST TOLERANCE 10%
J 2
(-5775 1975);
DISPLAY 0.617021 (-5775 1975);
PAINT SKYBLUE (-5775 1975);
FORCEPROP 1 LAST MATERIAL X7R
J 2
(-5775 1925);
DISPLAY 0.617021 (-5775 1925);
PAINT SKYBLUE (-5775 1925);
FORCEPROP 0 LAST GROUP PCIE_RISER
J 0
(-5907 2178);
DISPLAY 0.638298 (-5907 2178);
PAINT BROWN (-5907 2178);
DISPLAY BOTH (-5907 2178);
FORCEPROP 1 LAST PATH I12
J 2
(-5775 2175);
DISPLAY 0.978723 (-5775 2175);
PAINT WHITE (-5775 2175);
DISPLAY INVISIBLE (-5775 2175);
FORCEPROP 2 LAST CDS_LOCATION C827
J 2
(-5775 2125);
DISPLAY 0.617021 (-5775 2125);
PAINT AQUA (-5775 2125);
DISPLAY INVISIBLE (-5775 2125);
FORCEPROP 2 LAST CDS_LIB mstr_discrete
J 0
(-5725 2025);
PAINT MONO (-5725 2025);
DISPLAY INVISIBLE (-5725 2025);
FORCEPROP 2 LAST ROOM OCP_STEERING
J 2
(-5725 2025);
PAINT MONO (-5725 2025);
DISPLAY INVISIBLE (-5725 2025);
FORCEPROP 0 LAST SEC 1
J 0
(-5775 2175);
PAINT MONO (-5775 2175);
DISPLAY INVISIBLE (-5775 2175);
FORCEPROP 2 LAST SEC_TYPE 0402
J 0
(-5775 2225);
DISPLAY 1.021277 (-5775 2225);
PAINT ORANGE (-5775 2225);
DISPLAY INVISIBLE (-5775 2225);
FORCEADD TAP..3
(-5725 2275);
FORCEPROP 3 LASTPIN (-5725 2225) SIG_NAME P3E_CPU0_PE1_PCH_TXP<14>
J 0
(-5715 2235);
DISPLAY 0.659574 (-5715 2235);
PAINT MONO (-5715 2235);
DISPLAY INVISIBLE (-5715 2235);
FORCEPROP 1 LASTPIN (-5725 2225) BN 14
R 1
J 0
(-5732 2213);
DISPLAY 0.680851 (-5732 2213);
PAINT GREEN (-5732 2213);
FORCEPROP 1 LAST PATH I13
J 0
(-5727 2275);
DISPLAY 0.872340 (-5727 2275);
PAINT GREEN (-5727 2275);
DISPLAY INVISIBLE (-5727 2275);
FORCEPROP 2 LAST CDS_LIB mstr_standard
J 0
(-5725 2275);
PAINT MONO (-5725 2275);
DISPLAY INVISIBLE (-5725 2275);
FORCEPROP 1 LAST BODY_TYPE PLUMBING
J 0
(-5675 2225);
DISPLAY 2.276596 (-5675 2225);
PAINT GREEN (-5675 2225);
DISPLAY INVISIBLE (-5675 2225);
FORCEPROP 1 LAST HDL_TAP TRUE
J 0
(-5405 2145);
DISPLAY 2.276596 (-5405 2145);
PAINT GREEN (-5405 2145);
DISPLAY INVISIBLE (-5405 2145);
FORCEADD TAP..7
(-6025 2775);
FORCEPROP 3 LASTPIN (-6025 2825) SIG_NAME P3E_CPU0_PE1_PCH_CON_TXN<15>
J 0
(-6015 2835);
DISPLAY 0.659574 (-6015 2835);
PAINT MONO (-6015 2835);
DISPLAY INVISIBLE (-6015 2835);
FORCEPROP 1 LASTPIN (-6025 2825) BN 15
R 1
J 0
(-6032 2773);
DISPLAY 0.680851 (-6032 2773);
PAINT GREEN (-6032 2773);
FORCEPROP 1 LAST PATH I14
J 0
(-6027 2775);
DISPLAY 0.872340 (-6027 2775);
PAINT GREEN (-6027 2775);
DISPLAY INVISIBLE (-6027 2775);
FORCEPROP 2 LAST CDS_LIB mstr_standard
J 0
(-6025 2775);
PAINT MONO (-6025 2775);
DISPLAY INVISIBLE (-6025 2775);
FORCEPROP 1 LAST BODY_TYPE PLUMBING
J 0
(-5975 2775);
DISPLAY 2.276596 (-5975 2775);
PAINT GREEN (-5975 2775);
DISPLAY INVISIBLE (-5975 2775);
FORCEPROP 1 LAST HDL_TAP TRUE
J 0
(-5705 2645);
DISPLAY 2.276596 (-5705 2645);
PAINT GREEN (-5705 2645);
DISPLAY INVISIBLE (-5705 2645);
FORCEADD TAP..7
(-5825 2775);
FORCEPROP 3 LASTPIN (-5825 2825) SIG_NAME P3E_CPU0_PE1_PCH_CON_TXN<14>
J 0
(-5815 2835);
DISPLAY 0.659574 (-5815 2835);
PAINT MONO (-5815 2835);
DISPLAY INVISIBLE (-5815 2835);
FORCEPROP 1 LASTPIN (-5825 2825) BN 14
R 1
J 0
(-5832 2773);
DISPLAY 0.680851 (-5832 2773);
PAINT GREEN (-5832 2773);
FORCEPROP 1 LAST PATH I15
J 0
(-5827 2775);
DISPLAY 0.872340 (-5827 2775);
PAINT GREEN (-5827 2775);
DISPLAY INVISIBLE (-5827 2775);
FORCEPROP 2 LAST CDS_LIB mstr_standard
J 0
(-5825 2775);
PAINT MONO (-5825 2775);
DISPLAY INVISIBLE (-5825 2775);
FORCEPROP 1 LAST BODY_TYPE PLUMBING
J 0
(-5775 2775);
DISPLAY 2.276596 (-5775 2775);
PAINT GREEN (-5775 2775);
DISPLAY INVISIBLE (-5775 2775);
FORCEPROP 1 LAST HDL_TAP TRUE
J 0
(-5505 2645);
DISPLAY 2.276596 (-5505 2645);
PAINT GREEN (-5505 2645);
DISPLAY INVISIBLE (-5505 2645);
FORCEADD TAP..3
(-5525 2275);
FORCEPROP 3 LASTPIN (-5525 2225) SIG_NAME P3E_CPU0_PE1_PCH_TXP<13>
J 0
(-5515 2235);
DISPLAY 0.659574 (-5515 2235);
PAINT MONO (-5515 2235);
DISPLAY INVISIBLE (-5515 2235);
FORCEPROP 1 LASTPIN (-5525 2225) BN 13
R 1
J 0
(-5532 2213);
DISPLAY 0.680851 (-5532 2213);
PAINT GREEN (-5532 2213);
FORCEPROP 1 LAST PATH I16
J 0
(-5527 2275);
DISPLAY 0.872340 (-5527 2275);
PAINT GREEN (-5527 2275);
DISPLAY INVISIBLE (-5527 2275);
FORCEPROP 2 LAST CDS_LIB mstr_standard
J 0
(-5525 2275);
PAINT MONO (-5525 2275);
DISPLAY INVISIBLE (-5525 2275);
FORCEPROP 1 LAST BODY_TYPE PLUMBING
J 0
(-5475 2225);
DISPLAY 2.276596 (-5475 2225);
PAINT GREEN (-5475 2225);
DISPLAY INVISIBLE (-5475 2225);
FORCEPROP 1 LAST HDL_TAP TRUE
J 0
(-5205 2145);
DISPLAY 2.276596 (-5205 2145);
PAINT GREEN (-5205 2145);
DISPLAY INVISIBLE (-5205 2145);
FORCEADD CAP..1
R 2
(-5325 2025);
FORCEPROP 1 LAST VALUE 0.22UF
J 2
(-5375 2075);
DISPLAY 0.617021 (-5375 2075);
PAINT SKYBLUE (-5375 2075);
FORCEPROP 1 LAST $LOCATION C841
J 2
(-5375 2125);
DISPLAY 0.617021 (-5375 2125);
PAINT AQUA (-5375 2125);
FORCEPROP 1 LAST VOLTAGE 16V
J 2
(-5375 2025);
DISPLAY 0.617021 (-5375 2025);
PAINT SKYBLUE (-5375 2025);
FORCEPROP 1 LAST PART_NUMBER A36096-155
J 2
(-5375 1875);
DISPLAY 0.617021 (-5375 1875);
PAINT BLUE (-5375 1875);
FORCEPROP 1 LAST TOLERANCE 10%
J 2
(-5375 1975);
DISPLAY 0.617021 (-5375 1975);
PAINT SKYBLUE (-5375 1975);
FORCEPROP 1 LAST PACK_TYPE 0402
J 2
(-5375 1825);
DISPLAY 0.617021 (-5375 1825);
PAINT SKYBLUE (-5375 1825);
FORCEPROP 1 LASTPIN (-5325 1925) $PN 2
J 2
(-5335 1905);
DISPLAY 0.787234 (-5335 1905);
PAINT ORANGE (-5335 1905);
FORCEPROP 1 LASTPIN (-5325 2125) $PN 1
J 2
(-5335 2105);
DISPLAY 0.787234 (-5335 2105);
PAINT ORANGE (-5335 2105);
FORCEPROP 1 LAST MATERIAL X7R
J 2
(-5375 1925);
DISPLAY 0.617021 (-5375 1925);
PAINT SKYBLUE (-5375 1925);
FORCEPROP 0 LAST GROUP PCIE_RISER
J 0
(-5507 2178);
DISPLAY 0.638298 (-5507 2178);
PAINT BROWN (-5507 2178);
DISPLAY BOTH (-5507 2178);
FORCEPROP 1 LAST PATH I17
J 2
(-5375 2175);
DISPLAY 0.978723 (-5375 2175);
PAINT WHITE (-5375 2175);
DISPLAY INVISIBLE (-5375 2175);
FORCEPROP 2 LAST CDS_LOCATION C841
J 2
(-5375 2125);
DISPLAY 0.617021 (-5375 2125);
PAINT AQUA (-5375 2125);
DISPLAY INVISIBLE (-5375 2125);
FORCEPROP 2 LAST CDS_LIB mstr_discrete
J 0
(-5325 2025);
PAINT MONO (-5325 2025);
DISPLAY INVISIBLE (-5325 2025);
FORCEPROP 2 LAST ROOM OCP_STEERING
J 2
(-5325 2025);
PAINT MONO (-5325 2025);
DISPLAY INVISIBLE (-5325 2025);
FORCEPROP 0 LAST SEC 1
J 0
(-5375 2175);
PAINT MONO (-5375 2175);
DISPLAY INVISIBLE (-5375 2175);
FORCEPROP 2 LAST SEC_TYPE 0402
J 0
(-5375 2225);
DISPLAY 1.021277 (-5375 2225);
PAINT ORANGE (-5375 2225);
DISPLAY INVISIBLE (-5375 2225);
FORCEADD TAP..3
(-5325 2275);
FORCEPROP 3 LASTPIN (-5325 2225) SIG_NAME P3E_CPU0_PE1_PCH_TXP<12>
J 0
(-5315 2235);
DISPLAY 0.659574 (-5315 2235);
PAINT MONO (-5315 2235);
DISPLAY INVISIBLE (-5315 2235);
FORCEPROP 1 LASTPIN (-5325 2225) BN 12
R 1
J 0
(-5332 2213);
DISPLAY 0.680851 (-5332 2213);
PAINT GREEN (-5332 2213);
FORCEPROP 1 LAST PATH I18
J 0
(-5327 2275);
DISPLAY 0.872340 (-5327 2275);
PAINT GREEN (-5327 2275);
DISPLAY INVISIBLE (-5327 2275);
FORCEPROP 2 LAST CDS_LIB mstr_standard
J 0
(-5325 2275);
PAINT MONO (-5325 2275);
DISPLAY INVISIBLE (-5325 2275);
FORCEPROP 1 LAST BODY_TYPE PLUMBING
J 0
(-5275 2225);
DISPLAY 2.276596 (-5275 2225);
PAINT GREEN (-5275 2225);
DISPLAY INVISIBLE (-5275 2225);
FORCEPROP 1 LAST HDL_TAP TRUE
J 0
(-5005 2145);
DISPLAY 2.276596 (-5005 2145);
PAINT GREEN (-5005 2145);
DISPLAY INVISIBLE (-5005 2145);
FORCEADD TAP..3
(-5125 2275);
FORCEPROP 3 LASTPIN (-5125 2225) SIG_NAME P3E_CPU0_PE1_PCH_TXP<11>
J 0
(-5115 2235);
DISPLAY 0.659574 (-5115 2235);
PAINT MONO (-5115 2235);
DISPLAY INVISIBLE (-5115 2235);
FORCEPROP 1 LASTPIN (-5125 2225) BN 11
R 1
J 0
(-5132 2213);
DISPLAY 0.680851 (-5132 2213);
PAINT GREEN (-5132 2213);
FORCEPROP 1 LAST PATH I19
J 0
(-5127 2275);
DISPLAY 0.872340 (-5127 2275);
PAINT GREEN (-5127 2275);
DISPLAY INVISIBLE (-5127 2275);
FORCEPROP 2 LAST CDS_LIB mstr_standard
J 0
(-5125 2275);
PAINT MONO (-5125 2275);
DISPLAY INVISIBLE (-5125 2275);
FORCEPROP 1 LAST BODY_TYPE PLUMBING
J 0
(-5075 2225);
DISPLAY 2.276596 (-5075 2225);
PAINT GREEN (-5075 2225);
DISPLAY INVISIBLE (-5075 2225);
FORCEPROP 1 LAST HDL_TAP TRUE
J 0
(-4805 2145);
DISPLAY 2.276596 (-4805 2145);
PAINT GREEN (-4805 2145);
DISPLAY INVISIBLE (-4805 2145);
FORCEADD CAP..1
R 2
(-5925 1725);
FORCEPROP 1 LAST MATERIAL X7R
J 2
(-5975 1625);
DISPLAY 0.617021 (-5975 1625);
PAINT SKYBLUE (-5975 1625);
FORCEPROP 1 LAST TOLERANCE 10%
J 2
(-5975 1675);
DISPLAY 0.617021 (-5975 1675);
PAINT SKYBLUE (-5975 1675);
FORCEPROP 1 LAST PART_NUMBER A36096-155
J 2
(-5975 1575);
DISPLAY 0.617021 (-5975 1575);
PAINT BLUE (-5975 1575);
FORCEPROP 1 LAST $LOCATION C831
J 2
(-5975 1825);
DISPLAY 0.617021 (-5975 1825);
PAINT AQUA (-5975 1825);
FORCEPROP 1 LAST VOLTAGE 16V
J 2
(-5975 1725);
DISPLAY 0.617021 (-5975 1725);
PAINT SKYBLUE (-5975 1725);
FORCEPROP 1 LAST PACK_TYPE 0402
J 2
(-5975 1525);
DISPLAY 0.617021 (-5975 1525);
PAINT SKYBLUE (-5975 1525);
FORCEPROP 1 LASTPIN (-5925 1825) $PN 1
J 2
(-5935 1805);
DISPLAY 0.787234 (-5935 1805);
PAINT ORANGE (-5935 1805);
FORCEPROP 1 LASTPIN (-5925 1625) $PN 2
J 2
(-5935 1605);
DISPLAY 0.787234 (-5935 1605);
PAINT ORANGE (-5935 1605);
FORCEPROP 1 LAST VALUE 0.22UF
J 2
(-5975 1775);
DISPLAY 0.617021 (-5975 1775);
PAINT SKYBLUE (-5975 1775);
FORCEPROP 0 LAST GROUP PCIE_RISER
J 0
(-6307 1478);
DISPLAY 0.638298 (-6307 1478);
PAINT BROWN (-6307 1478);
DISPLAY BOTH (-6307 1478);
FORCEPROP 1 LAST PATH I2
J 2
(-5975 1875);
DISPLAY 0.978723 (-5975 1875);
PAINT WHITE (-5975 1875);
DISPLAY INVISIBLE (-5975 1875);
FORCEPROP 2 LAST CDS_LOCATION C831
J 2
(-5975 1825);
DISPLAY 0.617021 (-5975 1825);
PAINT AQUA (-5975 1825);
DISPLAY INVISIBLE (-5975 1825);
FORCEPROP 2 LAST CDS_LIB mstr_discrete
J 0
(-5925 1725);
PAINT MONO (-5925 1725);
DISPLAY INVISIBLE (-5925 1725);
FORCEPROP 2 LAST ROOM OCP_STEERING
J 2
(-5925 1725);
PAINT MONO (-5925 1725);
DISPLAY INVISIBLE (-5925 1725);
FORCEPROP 0 LAST SEC 1
J 0
(-5975 1875);
PAINT MONO (-5975 1875);
DISPLAY INVISIBLE (-5975 1875);
FORCEPROP 2 LAST SEC_TYPE 0402
J 0
(-5975 1925);
DISPLAY 1.021277 (-5975 1925);
PAINT ORANGE (-5975 1925);
DISPLAY INVISIBLE (-5975 1925);
FORCEADD TAP..7
(-5625 2775);
FORCEPROP 3 LASTPIN (-5625 2825) SIG_NAME P3E_CPU0_PE1_PCH_CON_TXN<13>
J 0
(-5615 2835);
DISPLAY 0.659574 (-5615 2835);
PAINT MONO (-5615 2835);
DISPLAY INVISIBLE (-5615 2835);
FORCEPROP 1 LASTPIN (-5625 2825) BN 13
R 1
J 0
(-5632 2773);
DISPLAY 0.680851 (-5632 2773);
PAINT GREEN (-5632 2773);
FORCEPROP 1 LAST PATH I20
J 0
(-5627 2775);
DISPLAY 0.872340 (-5627 2775);
PAINT GREEN (-5627 2775);
DISPLAY INVISIBLE (-5627 2775);
FORCEPROP 2 LAST CDS_LIB mstr_standard
J 0
(-5625 2775);
PAINT MONO (-5625 2775);
DISPLAY INVISIBLE (-5625 2775);
FORCEPROP 1 LAST BODY_TYPE PLUMBING
J 0
(-5575 2775);
DISPLAY 2.276596 (-5575 2775);
PAINT GREEN (-5575 2775);
DISPLAY INVISIBLE (-5575 2775);
FORCEPROP 1 LAST HDL_TAP TRUE
J 0
(-5305 2645);
DISPLAY 2.276596 (-5305 2645);
PAINT GREEN (-5305 2645);
DISPLAY INVISIBLE (-5305 2645);
FORCEADD TAP..7
(-5425 2775);
FORCEPROP 3 LASTPIN (-5425 2825) SIG_NAME P3E_CPU0_PE1_PCH_CON_TXN<12>
J 0
(-5415 2835);
DISPLAY 0.659574 (-5415 2835);
PAINT MONO (-5415 2835);
DISPLAY INVISIBLE (-5415 2835);
FORCEPROP 1 LASTPIN (-5425 2825) BN 12
R 1
J 0
(-5432 2773);
DISPLAY 0.680851 (-5432 2773);
PAINT GREEN (-5432 2773);
FORCEPROP 1 LAST PATH I21
J 0
(-5427 2775);
DISPLAY 0.872340 (-5427 2775);
PAINT GREEN (-5427 2775);
DISPLAY INVISIBLE (-5427 2775);
FORCEPROP 2 LAST CDS_LIB mstr_standard
J 0
(-5425 2775);
PAINT MONO (-5425 2775);
DISPLAY INVISIBLE (-5425 2775);
FORCEPROP 1 LAST BODY_TYPE PLUMBING
J 0
(-5375 2775);
DISPLAY 2.276596 (-5375 2775);
PAINT GREEN (-5375 2775);
DISPLAY INVISIBLE (-5375 2775);
FORCEPROP 1 LAST HDL_TAP TRUE
J 0
(-5105 2645);
DISPLAY 2.276596 (-5105 2645);
PAINT GREEN (-5105 2645);
DISPLAY INVISIBLE (-5105 2645);
FORCEADD TAP..7
(-5225 2775);
FORCEPROP 3 LASTPIN (-5225 2825) SIG_NAME P3E_CPU0_PE1_PCH_CON_TXN<11>
J 0
(-5215 2835);
DISPLAY 0.659574 (-5215 2835);
PAINT MONO (-5215 2835);
DISPLAY INVISIBLE (-5215 2835);
FORCEPROP 1 LASTPIN (-5225 2825) BN 11
R 1
J 0
(-5232 2773);
DISPLAY 0.680851 (-5232 2773);
PAINT GREEN (-5232 2773);
FORCEPROP 1 LAST PATH I22
J 0
(-5227 2775);
DISPLAY 0.872340 (-5227 2775);
PAINT GREEN (-5227 2775);
DISPLAY INVISIBLE (-5227 2775);
FORCEPROP 2 LAST CDS_LIB mstr_standard
J 0
(-5225 2775);
PAINT MONO (-5225 2775);
DISPLAY INVISIBLE (-5225 2775);
FORCEPROP 1 LAST BODY_TYPE PLUMBING
J 0
(-5175 2775);
DISPLAY 2.276596 (-5175 2775);
PAINT GREEN (-5175 2775);
DISPLAY INVISIBLE (-5175 2775);
FORCEPROP 1 LAST HDL_TAP TRUE
J 0
(-4905 2645);
DISPLAY 2.276596 (-4905 2645);
PAINT GREEN (-4905 2645);
DISPLAY INVISIBLE (-4905 2645);
FORCEADD CAP..1
R 2
(-6025 3025);
FORCEPROP 1 LASTPIN (-6025 2925) $PN 2
J 2
(-6035 2905);
DISPLAY 0.787234 (-6035 2905);
PAINT ORANGE (-6035 2905);
FORCEPROP 1 LASTPIN (-6025 3125) $PN 1
J 2
(-6035 3105);
DISPLAY 0.787234 (-6035 3105);
PAINT ORANGE (-6035 3105);
FORCEPROP 1 LAST PACK_TYPE 0402
J 2
(-6075 2825);
DISPLAY 0.617021 (-6075 2825);
PAINT SKYBLUE (-6075 2825);
FORCEPROP 1 LAST $LOCATION C830
J 2
(-6075 3125);
DISPLAY 0.617021 (-6075 3125);
PAINT AQUA (-6075 3125);
FORCEPROP 1 LAST VALUE 0.22UF
J 2
(-6075 3075);
DISPLAY 0.617021 (-6075 3075);
PAINT SKYBLUE (-6075 3075);
FORCEPROP 1 LAST MATERIAL X7R
J 2
(-6075 2925);
DISPLAY 0.617021 (-6075 2925);
PAINT SKYBLUE (-6075 2925);
FORCEPROP 1 LAST VOLTAGE 16V
J 2
(-6075 3025);
DISPLAY 0.617021 (-6075 3025);
PAINT SKYBLUE (-6075 3025);
FORCEPROP 1 LAST PART_NUMBER A36096-155
J 2
(-6075 2875);
DISPLAY 0.617021 (-6075 2875);
PAINT BLUE (-6075 2875);
FORCEPROP 1 LAST TOLERANCE 10%
J 2
(-6075 2975);
DISPLAY 0.617021 (-6075 2975);
PAINT SKYBLUE (-6075 2975);
FORCEPROP 0 LAST GROUP PCIE_RISER
J 0
(-6257 2778);
DISPLAY 0.638298 (-6257 2778);
PAINT BROWN (-6257 2778);
DISPLAY BOTH (-6257 2778);
FORCEPROP 2 LAST SEC_TYPE 0402
J 0
(-6075 3225);
DISPLAY 1.021277 (-6075 3225);
PAINT ORANGE (-6075 3225);
DISPLAY INVISIBLE (-6075 3225);
FORCEPROP 0 LAST SEC 1
J 0
(-6075 3175);
PAINT MONO (-6075 3175);
DISPLAY INVISIBLE (-6075 3175);
FORCEPROP 1 LAST PATH I23
J 2
(-6075 3175);
DISPLAY 0.978723 (-6075 3175);
PAINT WHITE (-6075 3175);
DISPLAY INVISIBLE (-6075 3175);
FORCEPROP 2 LAST CDS_LOCATION C830
J 2
(-6075 3125);
DISPLAY 0.617021 (-6075 3125);
PAINT AQUA (-6075 3125);
DISPLAY INVISIBLE (-6075 3125);
FORCEPROP 2 LAST ROOM OCP_STEERING
J 2
(-6025 3025);
PAINT MONO (-6025 3025);
DISPLAY INVISIBLE (-6025 3025);
FORCEPROP 2 LAST CDS_LIB mstr_discrete
J 0
(-6025 3025);
PAINT MONO (-6025 3025);
DISPLAY INVISIBLE (-6025 3025);
FORCEADD CAP..1
R 2
(-5825 3325);
FORCEPROP 1 LASTPIN (-5825 3225) $PN 2
J 2
(-5835 3205);
DISPLAY 0.787234 (-5835 3205);
PAINT ORANGE (-5835 3205);
FORCEPROP 1 LASTPIN (-5825 3425) $PN 1
J 2
(-5835 3405);
DISPLAY 0.787234 (-5835 3405);
PAINT ORANGE (-5835 3405);
FORCEPROP 1 LAST PACK_TYPE 0402
J 2
(-5875 3125);
DISPLAY 0.617021 (-5875 3125);
PAINT SKYBLUE (-5875 3125);
FORCEPROP 1 LAST VALUE 0.22UF
J 2
(-5875 3375);
DISPLAY 0.617021 (-5875 3375);
PAINT SKYBLUE (-5875 3375);
FORCEPROP 1 LAST VOLTAGE 16V
J 2
(-5875 3325);
DISPLAY 0.617021 (-5875 3325);
PAINT SKYBLUE (-5875 3325);
FORCEPROP 1 LAST TOLERANCE 10%
J 2
(-5875 3275);
DISPLAY 0.617021 (-5875 3275);
PAINT SKYBLUE (-5875 3275);
FORCEPROP 1 LAST MATERIAL X7R
J 2
(-5875 3225);
DISPLAY 0.617021 (-5875 3225);
PAINT SKYBLUE (-5875 3225);
FORCEPROP 1 LAST PART_NUMBER A36096-155
J 2
(-5875 3175);
DISPLAY 0.617021 (-5875 3175);
PAINT BLUE (-5875 3175);
FORCEPROP 1 LAST $LOCATION C826
J 2
(-5875 3425);
DISPLAY 0.617021 (-5875 3425);
PAINT AQUA (-5875 3425);
FORCEPROP 0 LAST GROUP PCIE_RISER
J 0
(-6007 3478);
DISPLAY 0.638298 (-6007 3478);
PAINT BROWN (-6007 3478);
DISPLAY BOTH (-6007 3478);
FORCEPROP 2 LAST SEC_TYPE 0402
J 0
(-5875 3525);
DISPLAY 1.021277 (-5875 3525);
PAINT ORANGE (-5875 3525);
DISPLAY INVISIBLE (-5875 3525);
FORCEPROP 0 LAST SEC 1
J 0
(-5875 3475);
PAINT MONO (-5875 3475);
DISPLAY INVISIBLE (-5875 3475);
FORCEPROP 1 LAST PATH I24
J 2
(-5875 3475);
DISPLAY 0.978723 (-5875 3475);
PAINT WHITE (-5875 3475);
DISPLAY INVISIBLE (-5875 3475);
FORCEPROP 2 LAST CDS_LOCATION C826
J 2
(-5875 3425);
DISPLAY 0.617021 (-5875 3425);
PAINT AQUA (-5875 3425);
DISPLAY INVISIBLE (-5875 3425);
FORCEPROP 2 LAST ROOM OCP_STEERING
J 2
(-5825 3325);
PAINT MONO (-5825 3325);
DISPLAY INVISIBLE (-5825 3325);
FORCEPROP 2 LAST CDS_LIB mstr_discrete
J 0
(-5825 3325);
PAINT MONO (-5825 3325);
DISPLAY INVISIBLE (-5825 3325);
FORCEADD TAP..3
(-6025 3575);
FORCEPROP 3 LASTPIN (-6025 3525) SIG_NAME P3E_CPU0_PE1_PCH_TXN<15>
J 0
(-6015 3535);
DISPLAY 0.659574 (-6015 3535);
PAINT MONO (-6015 3535);
DISPLAY INVISIBLE (-6015 3535);
FORCEPROP 1 LASTPIN (-6025 3525) BN 15
R 1
J 0
(-6032 3513);
DISPLAY 0.680851 (-6032 3513);
PAINT GREEN (-6032 3513);
FORCEPROP 1 LAST PATH I25
J 0
(-6027 3575);
DISPLAY 0.872340 (-6027 3575);
PAINT GREEN (-6027 3575);
DISPLAY INVISIBLE (-6027 3575);
FORCEPROP 2 LAST CDS_LIB mstr_standard
J 0
(-6025 3575);
PAINT MONO (-6025 3575);
DISPLAY INVISIBLE (-6025 3575);
FORCEPROP 1 LAST BODY_TYPE PLUMBING
J 0
(-5975 3525);
DISPLAY 2.276596 (-5975 3525);
PAINT GREEN (-5975 3525);
DISPLAY INVISIBLE (-5975 3525);
FORCEPROP 1 LAST HDL_TAP TRUE
J 0
(-5705 3445);
DISPLAY 2.276596 (-5705 3445);
PAINT GREEN (-5705 3445);
DISPLAY INVISIBLE (-5705 3445);
FORCEADD TAP..3
(-5825 3575);
FORCEPROP 3 LASTPIN (-5825 3525) SIG_NAME P3E_CPU0_PE1_PCH_TXN<14>
J 0
(-5815 3535);
DISPLAY 0.659574 (-5815 3535);
PAINT MONO (-5815 3535);
DISPLAY INVISIBLE (-5815 3535);
FORCEPROP 1 LASTPIN (-5825 3525) BN 14
R 1
J 0
(-5832 3513);
DISPLAY 0.680851 (-5832 3513);
PAINT GREEN (-5832 3513);
FORCEPROP 1 LAST PATH I26
J 0
(-5827 3575);
DISPLAY 0.872340 (-5827 3575);
PAINT GREEN (-5827 3575);
DISPLAY INVISIBLE (-5827 3575);
FORCEPROP 2 LAST CDS_LIB mstr_standard
J 0
(-5825 3575);
PAINT MONO (-5825 3575);
DISPLAY INVISIBLE (-5825 3575);
FORCEPROP 1 LAST BODY_TYPE PLUMBING
J 0
(-5775 3525);
DISPLAY 2.276596 (-5775 3525);
PAINT GREEN (-5775 3525);
DISPLAY INVISIBLE (-5775 3525);
FORCEPROP 1 LAST HDL_TAP TRUE
J 0
(-5505 3445);
DISPLAY 2.276596 (-5505 3445);
PAINT GREEN (-5505 3445);
DISPLAY INVISIBLE (-5505 3445);
FORCEADD TAP..3
(-5625 3575);
FORCEPROP 3 LASTPIN (-5625 3525) SIG_NAME P3E_CPU0_PE1_PCH_TXN<13>
J 0
(-5615 3535);
DISPLAY 0.659574 (-5615 3535);
PAINT MONO (-5615 3535);
DISPLAY INVISIBLE (-5615 3535);
FORCEPROP 1 LASTPIN (-5625 3525) BN 13
R 1
J 0
(-5632 3513);
DISPLAY 0.680851 (-5632 3513);
PAINT GREEN (-5632 3513);
FORCEPROP 1 LAST PATH I27
J 0
(-5627 3575);
DISPLAY 0.872340 (-5627 3575);
PAINT GREEN (-5627 3575);
DISPLAY INVISIBLE (-5627 3575);
FORCEPROP 2 LAST CDS_LIB mstr_standard
J 0
(-5625 3575);
PAINT MONO (-5625 3575);
DISPLAY INVISIBLE (-5625 3575);
FORCEPROP 1 LAST BODY_TYPE PLUMBING
J 0
(-5575 3525);
DISPLAY 2.276596 (-5575 3525);
PAINT GREEN (-5575 3525);
DISPLAY INVISIBLE (-5575 3525);
FORCEPROP 1 LAST HDL_TAP TRUE
J 0
(-5305 3445);
DISPLAY 2.276596 (-5305 3445);
PAINT GREEN (-5305 3445);
DISPLAY INVISIBLE (-5305 3445);
FORCEADD CAP..1
R 2
(-5625 3025);
FORCEPROP 1 LASTPIN (-5625 2925) $PN 2
J 2
(-5635 2905);
DISPLAY 0.787234 (-5635 2905);
PAINT ORANGE (-5635 2905);
FORCEPROP 1 LASTPIN (-5625 3125) $PN 1
J 2
(-5635 3105);
DISPLAY 0.787234 (-5635 3105);
PAINT ORANGE (-5635 3105);
FORCEPROP 1 LAST PACK_TYPE 0402
J 2
(-5675 2825);
DISPLAY 0.617021 (-5675 2825);
PAINT SKYBLUE (-5675 2825);
FORCEPROP 1 LAST VALUE 0.22UF
J 2
(-5675 3075);
DISPLAY 0.617021 (-5675 3075);
PAINT SKYBLUE (-5675 3075);
FORCEPROP 1 LAST TOLERANCE 10%
J 2
(-5675 2975);
DISPLAY 0.617021 (-5675 2975);
PAINT SKYBLUE (-5675 2975);
FORCEPROP 1 LAST $LOCATION C828
J 2
(-5675 3125);
DISPLAY 0.617021 (-5675 3125);
PAINT AQUA (-5675 3125);
FORCEPROP 1 LAST VOLTAGE 16V
J 2
(-5675 3025);
DISPLAY 0.617021 (-5675 3025);
PAINT SKYBLUE (-5675 3025);
FORCEPROP 1 LAST MATERIAL X7R
J 2
(-5675 2925);
DISPLAY 0.617021 (-5675 2925);
PAINT SKYBLUE (-5675 2925);
FORCEPROP 1 LAST PART_NUMBER A36096-155
J 2
(-5675 2875);
DISPLAY 0.617021 (-5675 2875);
PAINT BLUE (-5675 2875);
FORCEPROP 0 LAST GROUP PCIE_RISER
J 0
(-5807 2803);
DISPLAY 0.638298 (-5807 2803);
PAINT BROWN (-5807 2803);
DISPLAY BOTH (-5807 2803);
FORCEPROP 2 LAST SEC_TYPE 0402
J 0
(-5675 3225);
DISPLAY 1.021277 (-5675 3225);
PAINT ORANGE (-5675 3225);
DISPLAY INVISIBLE (-5675 3225);
FORCEPROP 0 LAST SEC 1
J 0
(-5675 3175);
PAINT MONO (-5675 3175);
DISPLAY INVISIBLE (-5675 3175);
FORCEPROP 1 LAST PATH I28
J 2
(-5675 3175);
DISPLAY 0.978723 (-5675 3175);
PAINT WHITE (-5675 3175);
DISPLAY INVISIBLE (-5675 3175);
FORCEPROP 2 LAST CDS_LOCATION C828
J 2
(-5675 3125);
DISPLAY 0.617021 (-5675 3125);
PAINT AQUA (-5675 3125);
DISPLAY INVISIBLE (-5675 3125);
FORCEPROP 2 LAST CDS_LIB mstr_discrete
J 0
(-5625 3025);
PAINT MONO (-5625 3025);
DISPLAY INVISIBLE (-5625 3025);
FORCEPROP 2 LAST ROOM OCP_STEERING
J 2
(-5625 3025);
PAINT MONO (-5625 3025);
DISPLAY INVISIBLE (-5625 3025);
FORCEADD CAP..1
R 2
(-5425 3325);
FORCEPROP 1 LASTPIN (-5425 3225) $PN 2
J 2
(-5435 3205);
DISPLAY 0.787234 (-5435 3205);
PAINT ORANGE (-5435 3205);
FORCEPROP 1 LASTPIN (-5425 3425) $PN 1
J 2
(-5435 3405);
DISPLAY 0.787234 (-5435 3405);
PAINT ORANGE (-5435 3405);
FORCEPROP 1 LAST PACK_TYPE 0402
J 2
(-5475 3125);
DISPLAY 0.617021 (-5475 3125);
PAINT SKYBLUE (-5475 3125);
FORCEPROP 1 LAST $LOCATION C840
J 2
(-5475 3425);
DISPLAY 0.617021 (-5475 3425);
PAINT AQUA (-5475 3425);
FORCEPROP 1 LAST VOLTAGE 16V
J 2
(-5475 3325);
DISPLAY 0.617021 (-5475 3325);
PAINT SKYBLUE (-5475 3325);
FORCEPROP 1 LAST TOLERANCE 10%
J 2
(-5475 3275);
DISPLAY 0.617021 (-5475 3275);
PAINT SKYBLUE (-5475 3275);
FORCEPROP 1 LAST PART_NUMBER A36096-155
J 2
(-5475 3175);
DISPLAY 0.617021 (-5475 3175);
PAINT BLUE (-5475 3175);
FORCEPROP 1 LAST VALUE 0.22UF
J 2
(-5475 3375);
DISPLAY 0.617021 (-5475 3375);
PAINT SKYBLUE (-5475 3375);
FORCEPROP 1 LAST MATERIAL X7R
J 2
(-5475 3225);
DISPLAY 0.617021 (-5475 3225);
PAINT SKYBLUE (-5475 3225);
FORCEPROP 0 LAST GROUP PCIE_RISER
J 0
(-5607 3478);
DISPLAY 0.638298 (-5607 3478);
PAINT BROWN (-5607 3478);
DISPLAY BOTH (-5607 3478);
FORCEPROP 2 LAST SEC_TYPE 0402
J 0
(-5475 3525);
DISPLAY 1.021277 (-5475 3525);
PAINT ORANGE (-5475 3525);
DISPLAY INVISIBLE (-5475 3525);
FORCEPROP 0 LAST SEC 1
J 0
(-5475 3475);
PAINT MONO (-5475 3475);
DISPLAY INVISIBLE (-5475 3475);
FORCEPROP 1 LAST PATH I29
J 2
(-5475 3475);
DISPLAY 0.978723 (-5475 3475);
PAINT WHITE (-5475 3475);
DISPLAY INVISIBLE (-5475 3475);
FORCEPROP 2 LAST CDS_LOCATION C840
J 2
(-5475 3425);
DISPLAY 0.617021 (-5475 3425);
PAINT AQUA (-5475 3425);
DISPLAY INVISIBLE (-5475 3425);
FORCEPROP 2 LAST CDS_LIB mstr_discrete
J 0
(-5425 3325);
PAINT MONO (-5425 3325);
DISPLAY INVISIBLE (-5425 3325);
FORCEPROP 2 LAST ROOM OCP_STEERING
J 2
(-5425 3325);
PAINT MONO (-5425 3325);
DISPLAY INVISIBLE (-5425 3325);
FORCEADD TAP..7
(-5725 1475);
FORCEPROP 3 LASTPIN (-5725 1525) SIG_NAME P3E_CPU0_PE1_PCH_CON_TXP<14>
J 0
(-5715 1535);
DISPLAY 0.659574 (-5715 1535);
PAINT MONO (-5715 1535);
DISPLAY INVISIBLE (-5715 1535);
FORCEPROP 1 LASTPIN (-5725 1525) BN 14
R 1
J 0
(-5732 1473);
DISPLAY 0.680851 (-5732 1473);
PAINT GREEN (-5732 1473);
FORCEPROP 1 LAST PATH I3
J 0
(-5727 1475);
DISPLAY 0.872340 (-5727 1475);
PAINT GREEN (-5727 1475);
DISPLAY INVISIBLE (-5727 1475);
FORCEPROP 2 LAST CDS_LIB mstr_standard
J 0
(-5725 1475);
PAINT MONO (-5725 1475);
DISPLAY INVISIBLE (-5725 1475);
FORCEPROP 1 LAST BODY_TYPE PLUMBING
J 0
(-5675 1475);
DISPLAY 2.276596 (-5675 1475);
PAINT GREEN (-5675 1475);
DISPLAY INVISIBLE (-5675 1475);
FORCEPROP 1 LAST HDL_TAP TRUE
J 0
(-5405 1345);
DISPLAY 2.276596 (-5405 1345);
PAINT GREEN (-5405 1345);
DISPLAY INVISIBLE (-5405 1345);
FORCEADD CAP..1
R 2
(-5225 3025);
FORCEPROP 1 LASTPIN (-5225 2925) $PN 2
J 2
(-5235 2905);
DISPLAY 0.787234 (-5235 2905);
PAINT ORANGE (-5235 2905);
FORCEPROP 1 LASTPIN (-5225 3125) $PN 1
J 2
(-5235 3105);
DISPLAY 0.787234 (-5235 3105);
PAINT ORANGE (-5235 3105);
FORCEPROP 1 LAST VOLTAGE 16V
J 2
(-5275 3025);
DISPLAY 0.617021 (-5275 3025);
PAINT SKYBLUE (-5275 3025);
FORCEPROP 1 LAST VALUE 0.22UF
J 2
(-5275 3075);
DISPLAY 0.617021 (-5275 3075);
PAINT SKYBLUE (-5275 3075);
FORCEPROP 1 LAST $LOCATION C832
J 2
(-5275 3125);
DISPLAY 0.617021 (-5275 3125);
PAINT AQUA (-5275 3125);
FORCEPROP 1 LAST TOLERANCE 10%
J 2
(-5275 2975);
DISPLAY 0.617021 (-5275 2975);
PAINT SKYBLUE (-5275 2975);
FORCEPROP 1 LAST MATERIAL X7R
J 2
(-5275 2925);
DISPLAY 0.617021 (-5275 2925);
PAINT SKYBLUE (-5275 2925);
FORCEPROP 1 LAST PART_NUMBER A36096-155
J 2
(-5275 2875);
DISPLAY 0.617021 (-5275 2875);
PAINT BLUE (-5275 2875);
FORCEPROP 1 LAST PACK_TYPE 0402
J 2
(-5275 2825);
DISPLAY 0.617021 (-5275 2825);
PAINT SKYBLUE (-5275 2825);
FORCEPROP 0 LAST GROUP PCIE_RISER
J 0
(-5407 2803);
DISPLAY 0.638298 (-5407 2803);
PAINT BROWN (-5407 2803);
DISPLAY BOTH (-5407 2803);
FORCEPROP 2 LAST SEC_TYPE 0402
J 0
(-5275 3225);
DISPLAY 1.021277 (-5275 3225);
PAINT ORANGE (-5275 3225);
DISPLAY INVISIBLE (-5275 3225);
FORCEPROP 0 LAST SEC 1
J 0
(-5275 3175);
PAINT MONO (-5275 3175);
DISPLAY INVISIBLE (-5275 3175);
FORCEPROP 1 LAST PATH I30
J 2
(-5275 3175);
DISPLAY 0.978723 (-5275 3175);
PAINT WHITE (-5275 3175);
DISPLAY INVISIBLE (-5275 3175);
FORCEPROP 2 LAST CDS_LOCATION C832
J 2
(-5275 3125);
DISPLAY 0.617021 (-5275 3125);
PAINT AQUA (-5275 3125);
DISPLAY INVISIBLE (-5275 3125);
FORCEPROP 2 LAST CDS_LIB mstr_discrete
J 0
(-5225 3025);
PAINT MONO (-5225 3025);
DISPLAY INVISIBLE (-5225 3025);
FORCEPROP 2 LAST ROOM OCP_STEERING
J 2
(-5225 3025);
PAINT MONO (-5225 3025);
DISPLAY INVISIBLE (-5225 3025);
FORCEADD TAP..3
(-5425 3575);
FORCEPROP 3 LASTPIN (-5425 3525) SIG_NAME P3E_CPU0_PE1_PCH_TXN<12>
J 0
(-5415 3535);
DISPLAY 0.659574 (-5415 3535);
PAINT MONO (-5415 3535);
DISPLAY INVISIBLE (-5415 3535);
FORCEPROP 1 LASTPIN (-5425 3525) BN 12
R 1
J 0
(-5432 3513);
DISPLAY 0.680851 (-5432 3513);
PAINT GREEN (-5432 3513);
FORCEPROP 1 LAST PATH I31
J 0
(-5427 3575);
DISPLAY 0.872340 (-5427 3575);
PAINT GREEN (-5427 3575);
DISPLAY INVISIBLE (-5427 3575);
FORCEPROP 2 LAST CDS_LIB mstr_standard
J 0
(-5425 3575);
PAINT MONO (-5425 3575);
DISPLAY INVISIBLE (-5425 3575);
FORCEPROP 1 LAST BODY_TYPE PLUMBING
J 0
(-5375 3525);
DISPLAY 2.276596 (-5375 3525);
PAINT GREEN (-5375 3525);
DISPLAY INVISIBLE (-5375 3525);
FORCEPROP 1 LAST HDL_TAP TRUE
J 0
(-5105 3445);
DISPLAY 2.276596 (-5105 3445);
PAINT GREEN (-5105 3445);
DISPLAY INVISIBLE (-5105 3445);
FORCEADD TAP..3
(-5225 3575);
FORCEPROP 3 LASTPIN (-5225 3525) SIG_NAME P3E_CPU0_PE1_PCH_TXN<11>
J 0
(-5215 3535);
DISPLAY 0.659574 (-5215 3535);
PAINT MONO (-5215 3535);
DISPLAY INVISIBLE (-5215 3535);
FORCEPROP 1 LASTPIN (-5225 3525) BN 11
R 1
J 0
(-5232 3513);
DISPLAY 0.680851 (-5232 3513);
PAINT GREEN (-5232 3513);
FORCEPROP 1 LAST PATH I32
J 0
(-5227 3575);
DISPLAY 0.872340 (-5227 3575);
PAINT GREEN (-5227 3575);
DISPLAY INVISIBLE (-5227 3575);
FORCEPROP 2 LAST CDS_LIB mstr_standard
J 0
(-5225 3575);
PAINT MONO (-5225 3575);
DISPLAY INVISIBLE (-5225 3575);
FORCEPROP 1 LAST BODY_TYPE PLUMBING
J 0
(-5175 3525);
DISPLAY 2.276596 (-5175 3525);
PAINT GREEN (-5175 3525);
DISPLAY INVISIBLE (-5175 3525);
FORCEPROP 1 LAST HDL_TAP TRUE
J 0
(-4905 3445);
DISPLAY 2.276596 (-4905 3445);
PAINT GREEN (-4905 3445);
DISPLAY INVISIBLE (-4905 3445);
FORCEADD TAP..7
(-4925 1475);
FORCEPROP 3 LASTPIN (-4925 1525) SIG_NAME P3E_CPU0_PE1_PCH_CON_TXP<10>
J 0
(-4915 1535);
DISPLAY 0.659574 (-4915 1535);
PAINT MONO (-4915 1535);
DISPLAY INVISIBLE (-4915 1535);
FORCEPROP 1 LASTPIN (-4925 1525) BN 10
R 1
J 0
(-4932 1473);
DISPLAY 0.680851 (-4932 1473);
PAINT GREEN (-4932 1473);
FORCEPROP 1 LAST PATH I33
J 0
(-4927 1475);
DISPLAY 0.872340 (-4927 1475);
PAINT GREEN (-4927 1475);
DISPLAY INVISIBLE (-4927 1475);
FORCEPROP 2 LAST CDS_LIB mstr_standard
J 0
(-4925 1475);
PAINT MONO (-4925 1475);
DISPLAY INVISIBLE (-4925 1475);
FORCEPROP 1 LAST BODY_TYPE PLUMBING
J 0
(-4875 1475);
DISPLAY 2.276596 (-4875 1475);
PAINT GREEN (-4875 1475);
DISPLAY INVISIBLE (-4875 1475);
FORCEPROP 1 LAST HDL_TAP TRUE
J 0
(-4605 1345);
DISPLAY 2.276596 (-4605 1345);
PAINT GREEN (-4605 1345);
DISPLAY INVISIBLE (-4605 1345);
FORCEADD TAP..7
(-4725 1475);
FORCEPROP 3 LASTPIN (-4725 1525) SIG_NAME P3E_CPU0_PE1_PCH_CON_TXP<9>
J 0
(-4715 1535);
DISPLAY 0.659574 (-4715 1535);
PAINT MONO (-4715 1535);
DISPLAY INVISIBLE (-4715 1535);
FORCEPROP 1 LASTPIN (-4725 1525) BN 9
R 1
J 0
(-4732 1473);
DISPLAY 0.680851 (-4732 1473);
PAINT GREEN (-4732 1473);
FORCEPROP 1 LAST PATH I34
J 0
(-4727 1475);
DISPLAY 0.872340 (-4727 1475);
PAINT GREEN (-4727 1475);
DISPLAY INVISIBLE (-4727 1475);
FORCEPROP 2 LAST CDS_LIB mstr_standard
J 0
(-4725 1475);
PAINT MONO (-4725 1475);
DISPLAY INVISIBLE (-4725 1475);
FORCEPROP 1 LAST BODY_TYPE PLUMBING
J 0
(-4675 1475);
DISPLAY 2.276596 (-4675 1475);
PAINT GREEN (-4675 1475);
DISPLAY INVISIBLE (-4675 1475);
FORCEPROP 1 LAST HDL_TAP TRUE
J 0
(-4405 1345);
DISPLAY 2.276596 (-4405 1345);
PAINT GREEN (-4405 1345);
DISPLAY INVISIBLE (-4405 1345);
FORCEADD CAP..1
R 2
(-4725 1725);
FORCEPROP 1 LAST PART_NUMBER A36096-155
J 2
(-4775 1575);
DISPLAY 0.617021 (-4775 1575);
PAINT BLUE (-4775 1575);
FORCEPROP 1 LAST MATERIAL X7R
J 2
(-4775 1625);
DISPLAY 0.617021 (-4775 1625);
PAINT SKYBLUE (-4775 1625);
FORCEPROP 1 LAST TOLERANCE 10%
J 2
(-4775 1675);
DISPLAY 0.617021 (-4775 1675);
PAINT SKYBLUE (-4775 1675);
FORCEPROP 1 LAST $LOCATION C845
J 2
(-4775 1825);
DISPLAY 0.617021 (-4775 1825);
PAINT AQUA (-4775 1825);
FORCEPROP 1 LAST VALUE 0.22UF
J 2
(-4775 1775);
DISPLAY 0.617021 (-4775 1775);
PAINT SKYBLUE (-4775 1775);
FORCEPROP 1 LAST VOLTAGE 16V
J 2
(-4775 1725);
DISPLAY 0.617021 (-4775 1725);
PAINT SKYBLUE (-4775 1725);
FORCEPROP 1 LAST PACK_TYPE 0402
J 2
(-4775 1525);
DISPLAY 0.617021 (-4775 1525);
PAINT SKYBLUE (-4775 1525);
FORCEPROP 1 LASTPIN (-4725 1625) $PN 2
J 2
(-4735 1605);
DISPLAY 0.787234 (-4735 1605);
PAINT ORANGE (-4735 1605);
FORCEPROP 0 LAST GROUP PCIE_RISER
J 0
(-4907 1503);
DISPLAY 0.638298 (-4907 1503);
PAINT BROWN (-4907 1503);
DISPLAY BOTH (-4907 1503);
FORCEPROP 1 LASTPIN (-4725 1825) $PN 1
J 2
(-4735 1805);
DISPLAY 0.787234 (-4735 1805);
PAINT ORANGE (-4735 1805);
FORCEPROP 1 LAST PATH I35
J 2
(-4775 1875);
DISPLAY 0.978723 (-4775 1875);
PAINT WHITE (-4775 1875);
DISPLAY INVISIBLE (-4775 1875);
FORCEPROP 2 LAST CDS_LOCATION C845
J 2
(-4775 1825);
DISPLAY 0.617021 (-4775 1825);
PAINT AQUA (-4775 1825);
DISPLAY INVISIBLE (-4775 1825);
FORCEPROP 2 LAST CDS_LIB mstr_discrete
J 0
(-4725 1725);
PAINT MONO (-4725 1725);
DISPLAY INVISIBLE (-4725 1725);
FORCEPROP 2 LAST ROOM OCP_STEERING
J 2
(-4725 1725);
PAINT MONO (-4725 1725);
DISPLAY INVISIBLE (-4725 1725);
FORCEPROP 0 LAST SEC 1
J 0
(-4775 1875);
PAINT MONO (-4775 1875);
DISPLAY INVISIBLE (-4775 1875);
FORCEPROP 2 LAST SEC_TYPE 0402
J 0
(-4775 1925);
DISPLAY 1.021277 (-4775 1925);
PAINT ORANGE (-4775 1925);
DISPLAY INVISIBLE (-4775 1925);
FORCEADD TAP..7
(-4525 1475);
FORCEPROP 3 LASTPIN (-4525 1525) SIG_NAME P3E_CPU0_PE1_PCH_CON_TXP<8>
J 0
(-4515 1535);
DISPLAY 0.659574 (-4515 1535);
PAINT MONO (-4515 1535);
DISPLAY INVISIBLE (-4515 1535);
FORCEPROP 1 LASTPIN (-4525 1525) BN 8
R 1
J 0
(-4532 1473);
DISPLAY 0.680851 (-4532 1473);
PAINT GREEN (-4532 1473);
FORCEPROP 1 LAST PATH I36
J 0
(-4527 1475);
DISPLAY 0.872340 (-4527 1475);
PAINT GREEN (-4527 1475);
DISPLAY INVISIBLE (-4527 1475);
FORCEPROP 2 LAST CDS_LIB mstr_standard
J 0
(-4525 1475);
PAINT MONO (-4525 1475);
DISPLAY INVISIBLE (-4525 1475);
FORCEPROP 1 LAST BODY_TYPE PLUMBING
J 0
(-4475 1475);
DISPLAY 2.276596 (-4475 1475);
PAINT GREEN (-4475 1475);
DISPLAY INVISIBLE (-4475 1475);
FORCEPROP 1 LAST HDL_TAP TRUE
J 0
(-4205 1345);
DISPLAY 2.276596 (-4205 1345);
PAINT GREEN (-4205 1345);
DISPLAY INVISIBLE (-4205 1345);
FORCEADD OFFPAGE..2
(-4225 1425);
FORCEPROP 2 LAST $XR0 108 
J 0
(-4036 1425);
DISPLAY 0.638298 (-4036 1425);
PAINT MONO (-4036 1425);
FORCEPROP 2 LAST PATH I37
J 0
(-4025 1475);
DISPLAY 1.021277 (-4025 1475);
PAINT ORANGE (-4025 1475);
DISPLAY INVISIBLE (-4025 1475);
FORCEPROP 2 LAST CDS_LIB mstr_standard
J 0
(-4225 1425);
PAINT MONO (-4225 1425);
DISPLAY INVISIBLE (-4225 1425);
FORCEPROP 1 LAST OFFPAGE TRUE
J 0
(-3900 1300);
DISPLAY 0.872340 (-3900 1300);
PAINT GREEN (-3900 1300);
DISPLAY INVISIBLE (-3900 1300);
FORCEPROP 1 LAST COMMENT_BODY TRUE
J 0
(-4270 1330);
DISPLAY 0.872340 (-4270 1330);
PAINT GREEN (-4270 1330);
DISPLAY INVISIBLE (-4270 1330);
FORCEADD TAP..7
(-3425 1475);
FORCEPROP 3 LASTPIN (-3425 1525) SIG_NAME P3E_CPU0_PE1_PCH_CON_RXP<15>
J 0
(-3415 1535);
DISPLAY 0.659574 (-3415 1535);
PAINT MONO (-3415 1535);
DISPLAY INVISIBLE (-3415 1535);
FORCEPROP 1 LASTPIN (-3425 1525) BN 15
R 1
J 0
(-3432 1473);
DISPLAY 0.680851 (-3432 1473);
PAINT GREEN (-3432 1473);
FORCEPROP 2 LAST CDS_LIB mstr_standard
J 0
(-3425 1475);
PAINT MONO (-3425 1475);
DISPLAY INVISIBLE (-3425 1475);
FORCEPROP 1 LAST PATH I38
J 0
(-3427 1475);
DISPLAY 0.872340 (-3427 1475);
PAINT GREEN (-3427 1475);
DISPLAY INVISIBLE (-3427 1475);
FORCEPROP 1 LAST BODY_TYPE PLUMBING
J 0
(-3375 1475);
DISPLAY 2.276596 (-3375 1475);
PAINT GREEN (-3375 1475);
DISPLAY INVISIBLE (-3375 1475);
FORCEPROP 1 LAST HDL_TAP TRUE
J 0
(-3105 1345);
DISPLAY 2.276596 (-3105 1345);
PAINT GREEN (-3105 1345);
DISPLAY INVISIBLE (-3105 1345);
FORCEADD RES..2
(-3425 1725);
FORCEPROP 1 LAST WATTAGE 1/16W
J 0
(-3385 1700);
DISPLAY 0.617021 (-3385 1700);
PAINT SKYBLUE (-3385 1700);
FORCEPROP 1 LASTPIN (-3425 1625) $PN 2
J 0
(-3420 1635);
DISPLAY 0.787234 (-3420 1635);
PAINT ORANGE (-3420 1635);
FORCEPROP 1 LAST TOLERANCE 5%
J 0
(-3380 1750);
DISPLAY 0.617021 (-3380 1750);
PAINT SKYBLUE (-3380 1750);
FORCEPROP 1 LAST MATERIAL CHIP
J 0
(-3385 1650);
DISPLAY 0.617021 (-3385 1650);
PAINT SKYBLUE (-3385 1650);
FORCEPROP 1 LASTPIN (-3425 1825) $PN 1
J 0
(-3420 1787);
DISPLAY 0.787234 (-3420 1787);
PAINT ORANGE (-3420 1787);
FORCEPROP 1 LAST VALUE 0.0
J 0
(-3380 1800);
DISPLAY 0.617021 (-3380 1800);
PAINT SKYBLUE (-3380 1800);
FORCEPROP 1 LAST PACK_TYPE 0402
J 0
(-3360 1550);
DISPLAY 0.617021 (-3360 1550);
PAINT SKYBLUE (-3360 1550);
FORCEPROP 1 LAST $LOCATION R767
J 0
(-3380 1850);
DISPLAY 0.617021 (-3380 1850);
PAINT AQUA (-3380 1850);
FORCEPROP 1 LAST PART_NUMBER G21497-005
J 0
(-3385 1600);
DISPLAY 0.617021 (-3385 1600);
PAINT BLUE (-3385 1600);
FORCEPROP 0 LAST GROUP PCIE_RISER
J 0
(-3407 1503);
DISPLAY 0.638298 (-3407 1503);
PAINT BROWN (-3407 1503);
DISPLAY BOTH (-3407 1503);
FORCEPROP 1 LAST PATH I39
J 0
(-3375 1900);
DISPLAY 0.978723 (-3375 1900);
PAINT WHITE (-3375 1900);
DISPLAY INVISIBLE (-3375 1900);
FORCEPROP 0 LAST CDS_LOCATION R767
J 0
(-3375 1900);
PAINT MONO (-3375 1900);
DISPLAY INVISIBLE (-3375 1900);
FORCEPROP 2 LAST CDS_LIB mstr_discrete
J 0
(-3425 1725);
PAINT MONO (-3425 1725);
DISPLAY INVISIBLE (-3425 1725);
FORCEPROP 2 LAST ROOM PCIE_STEERING
J 0
(-3375 1900);
PAINT MONO (-3375 1900);
DISPLAY INVISIBLE (-3375 1900);
FORCEPROP 0 LAST SEC 1
J 0
(-3375 1900);
PAINT MONO (-3375 1900);
DISPLAY INVISIBLE (-3375 1900);
FORCEPROP 2 LAST SEC_TYPE 0402
J 0
(-3375 1950);
DISPLAY 1.021277 (-3375 1950);
PAINT ORANGE (-3375 1950);
DISPLAY INVISIBLE (-3375 1950);
FORCEADD TAP..7
(-5525 1475);
FORCEPROP 3 LASTPIN (-5525 1525) SIG_NAME P3E_CPU0_PE1_PCH_CON_TXP<13>
J 0
(-5515 1535);
DISPLAY 0.659574 (-5515 1535);
PAINT MONO (-5515 1535);
DISPLAY INVISIBLE (-5515 1535);
FORCEPROP 1 LASTPIN (-5525 1525) BN 13
R 1
J 0
(-5532 1473);
DISPLAY 0.680851 (-5532 1473);
PAINT GREEN (-5532 1473);
FORCEPROP 1 LAST PATH I4
J 0
(-5527 1475);
DISPLAY 0.872340 (-5527 1475);
PAINT GREEN (-5527 1475);
DISPLAY INVISIBLE (-5527 1475);
FORCEPROP 2 LAST CDS_LIB mstr_standard
J 0
(-5525 1475);
PAINT MONO (-5525 1475);
DISPLAY INVISIBLE (-5525 1475);
FORCEPROP 1 LAST BODY_TYPE PLUMBING
J 0
(-5475 1475);
DISPLAY 2.276596 (-5475 1475);
PAINT GREEN (-5475 1475);
DISPLAY INVISIBLE (-5475 1475);
FORCEPROP 1 LAST HDL_TAP TRUE
J 0
(-5205 1345);
DISPLAY 2.276596 (-5205 1345);
PAINT GREEN (-5205 1345);
DISPLAY INVISIBLE (-5205 1345);
FORCEADD TAP..7
(-3225 1475);
FORCEPROP 3 LASTPIN (-3225 1525) SIG_NAME P3E_CPU0_PE1_PCH_CON_RXP<14>
J 0
(-3215 1535);
DISPLAY 0.659574 (-3215 1535);
PAINT MONO (-3215 1535);
DISPLAY INVISIBLE (-3215 1535);
FORCEPROP 1 LASTPIN (-3225 1525) BN 14
R 1
J 0
(-3232 1473);
DISPLAY 0.680851 (-3232 1473);
PAINT GREEN (-3232 1473);
FORCEPROP 1 LAST PATH I40
J 0
(-3227 1475);
DISPLAY 0.872340 (-3227 1475);
PAINT GREEN (-3227 1475);
DISPLAY INVISIBLE (-3227 1475);
FORCEPROP 2 LAST CDS_LIB mstr_standard
J 0
(-3225 1475);
PAINT MONO (-3225 1475);
DISPLAY INVISIBLE (-3225 1475);
FORCEPROP 1 LAST BODY_TYPE PLUMBING
J 0
(-3175 1475);
DISPLAY 2.276596 (-3175 1475);
PAINT GREEN (-3175 1475);
DISPLAY INVISIBLE (-3175 1475);
FORCEPROP 1 LAST HDL_TAP TRUE
J 0
(-2905 1345);
DISPLAY 2.276596 (-2905 1345);
PAINT GREEN (-2905 1345);
DISPLAY INVISIBLE (-2905 1345);
FORCEADD CAP..1
R 2
(-4925 2025);
FORCEPROP 1 LAST PACK_TYPE 0402
J 2
(-4975 1825);
DISPLAY 0.617021 (-4975 1825);
PAINT SKYBLUE (-4975 1825);
FORCEPROP 1 LASTPIN (-4925 2125) $PN 1
J 2
(-4935 2105);
DISPLAY 0.787234 (-4935 2105);
PAINT ORANGE (-4935 2105);
FORCEPROP 1 LAST $LOCATION C835
J 2
(-4975 2125);
DISPLAY 0.617021 (-4975 2125);
PAINT AQUA (-4975 2125);
FORCEPROP 1 LAST VALUE 0.22UF
J 2
(-4975 2075);
DISPLAY 0.617021 (-4975 2075);
PAINT SKYBLUE (-4975 2075);
FORCEPROP 1 LAST VOLTAGE 16V
J 2
(-4975 2025);
DISPLAY 0.617021 (-4975 2025);
PAINT SKYBLUE (-4975 2025);
FORCEPROP 1 LAST TOLERANCE 10%
J 2
(-4975 1975);
DISPLAY 0.617021 (-4975 1975);
PAINT SKYBLUE (-4975 1975);
FORCEPROP 1 LAST MATERIAL X7R
J 2
(-4975 1925);
DISPLAY 0.617021 (-4975 1925);
PAINT SKYBLUE (-4975 1925);
FORCEPROP 1 LASTPIN (-4925 1925) $PN 2
J 2
(-4935 1905);
DISPLAY 0.787234 (-4935 1905);
PAINT ORANGE (-4935 1905);
FORCEPROP 1 LAST PART_NUMBER A36096-155
J 2
(-4975 1875);
DISPLAY 0.617021 (-4975 1875);
PAINT BLUE (-4975 1875);
FORCEPROP 0 LAST GROUP PCIE_RISER
J 0
(-5082 2153);
DISPLAY 0.638298 (-5082 2153);
PAINT BROWN (-5082 2153);
DISPLAY BOTH (-5082 2153);
FORCEPROP 1 LAST PATH I41
J 2
(-4975 2175);
DISPLAY 0.978723 (-4975 2175);
PAINT WHITE (-4975 2175);
DISPLAY INVISIBLE (-4975 2175);
FORCEPROP 2 LAST CDS_LOCATION C835
J 2
(-4975 2125);
DISPLAY 0.617021 (-4975 2125);
PAINT AQUA (-4975 2125);
DISPLAY INVISIBLE (-4975 2125);
FORCEPROP 2 LAST CDS_LIB mstr_discrete
J 0
(-4925 2025);
PAINT MONO (-4925 2025);
DISPLAY INVISIBLE (-4925 2025);
FORCEPROP 2 LAST ROOM OCP_STEERING
J 2
(-4925 2025);
PAINT MONO (-4925 2025);
DISPLAY INVISIBLE (-4925 2025);
FORCEPROP 0 LAST SEC 1
J 0
(-4975 2175);
PAINT MONO (-4975 2175);
DISPLAY INVISIBLE (-4975 2175);
FORCEPROP 2 LAST SEC_TYPE 0402
J 0
(-4975 2225);
DISPLAY 1.021277 (-4975 2225);
PAINT ORANGE (-4975 2225);
DISPLAY INVISIBLE (-4975 2225);
FORCEADD TAP..3
(-4925 2275);
FORCEPROP 3 LASTPIN (-4925 2225) SIG_NAME P3E_CPU0_PE1_PCH_TXP<10>
J 0
(-4915 2235);
DISPLAY 0.659574 (-4915 2235);
PAINT MONO (-4915 2235);
DISPLAY INVISIBLE (-4915 2235);
FORCEPROP 1 LASTPIN (-4925 2225) BN 10
R 1
J 0
(-4932 2213);
DISPLAY 0.680851 (-4932 2213);
PAINT GREEN (-4932 2213);
FORCEPROP 1 LAST PATH I42
J 0
(-4927 2275);
DISPLAY 0.872340 (-4927 2275);
PAINT GREEN (-4927 2275);
DISPLAY INVISIBLE (-4927 2275);
FORCEPROP 2 LAST CDS_LIB mstr_standard
J 0
(-4925 2275);
PAINT MONO (-4925 2275);
DISPLAY INVISIBLE (-4925 2275);
FORCEPROP 1 LAST BODY_TYPE PLUMBING
J 0
(-4875 2225);
DISPLAY 2.276596 (-4875 2225);
PAINT GREEN (-4875 2225);
DISPLAY INVISIBLE (-4875 2225);
FORCEPROP 1 LAST HDL_TAP TRUE
J 0
(-4605 2145);
DISPLAY 2.276596 (-4605 2145);
PAINT GREEN (-4605 2145);
DISPLAY INVISIBLE (-4605 2145);
FORCEADD TAP..3
(-4725 2275);
FORCEPROP 3 LASTPIN (-4725 2225) SIG_NAME P3E_CPU0_PE1_PCH_TXP<9>
J 0
(-4715 2235);
DISPLAY 0.659574 (-4715 2235);
PAINT MONO (-4715 2235);
DISPLAY INVISIBLE (-4715 2235);
FORCEPROP 1 LASTPIN (-4725 2225) BN 9
R 1
J 0
(-4732 2213);
DISPLAY 0.680851 (-4732 2213);
PAINT GREEN (-4732 2213);
FORCEPROP 1 LAST PATH I43
J 0
(-4727 2275);
DISPLAY 0.872340 (-4727 2275);
PAINT GREEN (-4727 2275);
DISPLAY INVISIBLE (-4727 2275);
FORCEPROP 2 LAST CDS_LIB mstr_standard
J 0
(-4725 2275);
PAINT MONO (-4725 2275);
DISPLAY INVISIBLE (-4725 2275);
FORCEPROP 1 LAST BODY_TYPE PLUMBING
J 0
(-4675 2225);
DISPLAY 2.276596 (-4675 2225);
PAINT GREEN (-4675 2225);
DISPLAY INVISIBLE (-4675 2225);
FORCEPROP 1 LAST HDL_TAP TRUE
J 0
(-4405 2145);
DISPLAY 2.276596 (-4405 2145);
PAINT GREEN (-4405 2145);
DISPLAY INVISIBLE (-4405 2145);
FORCEADD TAP..7
(-5025 2775);
FORCEPROP 3 LASTPIN (-5025 2825) SIG_NAME P3E_CPU0_PE1_PCH_CON_TXN<10>
J 0
(-5015 2835);
DISPLAY 0.659574 (-5015 2835);
PAINT MONO (-5015 2835);
DISPLAY INVISIBLE (-5015 2835);
FORCEPROP 1 LASTPIN (-5025 2825) BN 10
R 1
J 0
(-5032 2773);
DISPLAY 0.680851 (-5032 2773);
PAINT GREEN (-5032 2773);
FORCEPROP 1 LAST PATH I44
J 0
(-5027 2775);
DISPLAY 0.872340 (-5027 2775);
PAINT GREEN (-5027 2775);
DISPLAY INVISIBLE (-5027 2775);
FORCEPROP 2 LAST CDS_LIB mstr_standard
J 0
(-5025 2775);
PAINT MONO (-5025 2775);
DISPLAY INVISIBLE (-5025 2775);
FORCEPROP 1 LAST BODY_TYPE PLUMBING
J 0
(-4975 2775);
DISPLAY 2.276596 (-4975 2775);
PAINT GREEN (-4975 2775);
DISPLAY INVISIBLE (-4975 2775);
FORCEPROP 1 LAST HDL_TAP TRUE
J 0
(-4705 2645);
DISPLAY 2.276596 (-4705 2645);
PAINT GREEN (-4705 2645);
DISPLAY INVISIBLE (-4705 2645);
FORCEADD TAP..7
(-4825 2775);
FORCEPROP 3 LASTPIN (-4825 2825) SIG_NAME P3E_CPU0_PE1_PCH_CON_TXN<9>
J 0
(-4815 2835);
DISPLAY 0.659574 (-4815 2835);
PAINT MONO (-4815 2835);
DISPLAY INVISIBLE (-4815 2835);
FORCEPROP 1 LASTPIN (-4825 2825) BN 9
R 1
J 0
(-4832 2773);
DISPLAY 0.680851 (-4832 2773);
PAINT GREEN (-4832 2773);
FORCEPROP 1 LAST PATH I45
J 0
(-4827 2775);
DISPLAY 0.872340 (-4827 2775);
PAINT GREEN (-4827 2775);
DISPLAY INVISIBLE (-4827 2775);
FORCEPROP 2 LAST CDS_LIB mstr_standard
J 0
(-4825 2775);
PAINT MONO (-4825 2775);
DISPLAY INVISIBLE (-4825 2775);
FORCEPROP 1 LAST BODY_TYPE PLUMBING
J 0
(-4775 2775);
DISPLAY 2.276596 (-4775 2775);
PAINT GREEN (-4775 2775);
DISPLAY INVISIBLE (-4775 2775);
FORCEPROP 1 LAST HDL_TAP TRUE
J 0
(-4505 2645);
DISPLAY 2.276596 (-4505 2645);
PAINT GREEN (-4505 2645);
DISPLAY INVISIBLE (-4505 2645);
FORCEADD TAP..7
(-4625 2775);
FORCEPROP 3 LASTPIN (-4625 2825) SIG_NAME P3E_CPU0_PE1_PCH_CON_TXN<8>
J 0
(-4615 2835);
DISPLAY 0.659574 (-4615 2835);
PAINT MONO (-4615 2835);
DISPLAY INVISIBLE (-4615 2835);
FORCEPROP 1 LASTPIN (-4625 2825) BN 8
R 1
J 0
(-4632 2773);
DISPLAY 0.680851 (-4632 2773);
PAINT GREEN (-4632 2773);
FORCEPROP 1 LAST PATH I46
J 0
(-4627 2775);
DISPLAY 0.872340 (-4627 2775);
PAINT GREEN (-4627 2775);
DISPLAY INVISIBLE (-4627 2775);
FORCEPROP 2 LAST CDS_LIB mstr_standard
J 0
(-4625 2775);
PAINT MONO (-4625 2775);
DISPLAY INVISIBLE (-4625 2775);
FORCEPROP 1 LAST BODY_TYPE PLUMBING
J 0
(-4575 2775);
DISPLAY 2.276596 (-4575 2775);
PAINT GREEN (-4575 2775);
DISPLAY INVISIBLE (-4575 2775);
FORCEPROP 1 LAST HDL_TAP TRUE
J 0
(-4305 2645);
DISPLAY 2.276596 (-4305 2645);
PAINT GREEN (-4305 2645);
DISPLAY INVISIBLE (-4305 2645);
FORCEADD CAP..1
R 2
(-4525 2025);
FORCEPROP 1 LAST PACK_TYPE 0402
J 2
(-4575 1825);
DISPLAY 0.617021 (-4575 1825);
PAINT SKYBLUE (-4575 1825);
FORCEPROP 1 LASTPIN (-4525 2125) $PN 1
J 2
(-4535 2105);
DISPLAY 0.787234 (-4535 2105);
PAINT ORANGE (-4535 2105);
FORCEPROP 1 LASTPIN (-4525 1925) $PN 2
J 2
(-4535 1905);
DISPLAY 0.787234 (-4535 1905);
PAINT ORANGE (-4535 1905);
FORCEPROP 1 LAST PART_NUMBER A36096-155
J 2
(-4575 1875);
DISPLAY 0.617021 (-4575 1875);
PAINT BLUE (-4575 1875);
FORCEPROP 1 LAST MATERIAL X7R
J 2
(-4575 1925);
DISPLAY 0.617021 (-4575 1925);
PAINT SKYBLUE (-4575 1925);
FORCEPROP 1 LAST TOLERANCE 10%
J 2
(-4575 1975);
DISPLAY 0.617021 (-4575 1975);
PAINT SKYBLUE (-4575 1975);
FORCEPROP 1 LAST VALUE 0.22UF
J 2
(-4575 2075);
DISPLAY 0.617021 (-4575 2075);
PAINT SKYBLUE (-4575 2075);
FORCEPROP 1 LAST VOLTAGE 16V
J 2
(-4575 2025);
DISPLAY 0.617021 (-4575 2025);
PAINT SKYBLUE (-4575 2025);
FORCEPROP 1 LAST $LOCATION C843
J 2
(-4575 2125);
DISPLAY 0.617021 (-4575 2125);
PAINT AQUA (-4575 2125);
FORCEPROP 0 LAST GROUP PCIE_RISER
J 0
(-4682 2153);
DISPLAY 0.638298 (-4682 2153);
PAINT BROWN (-4682 2153);
DISPLAY BOTH (-4682 2153);
FORCEPROP 1 LAST PATH I47
J 2
(-4575 2175);
DISPLAY 0.978723 (-4575 2175);
PAINT WHITE (-4575 2175);
DISPLAY INVISIBLE (-4575 2175);
FORCEPROP 2 LAST CDS_LOCATION C843
J 2
(-4575 2125);
DISPLAY 0.617021 (-4575 2125);
PAINT AQUA (-4575 2125);
DISPLAY INVISIBLE (-4575 2125);
FORCEPROP 2 LAST CDS_LIB mstr_discrete
J 0
(-4525 2025);
PAINT MONO (-4525 2025);
DISPLAY INVISIBLE (-4525 2025);
FORCEPROP 2 LAST ROOM OCP_STEERING
J 2
(-4525 2025);
PAINT MONO (-4525 2025);
DISPLAY INVISIBLE (-4525 2025);
FORCEPROP 0 LAST SEC 1
J 0
(-4575 2175);
PAINT MONO (-4575 2175);
DISPLAY INVISIBLE (-4575 2175);
FORCEPROP 2 LAST SEC_TYPE 0402
J 0
(-4575 2225);
DISPLAY 1.021277 (-4575 2225);
PAINT ORANGE (-4575 2225);
DISPLAY INVISIBLE (-4575 2225);
FORCEADD TAP..3
(-4525 2275);
FORCEPROP 3 LASTPIN (-4525 2225) SIG_NAME P3E_CPU0_PE1_PCH_TXP<8>
J 0
(-4515 2235);
DISPLAY 0.659574 (-4515 2235);
PAINT MONO (-4515 2235);
DISPLAY INVISIBLE (-4515 2235);
FORCEPROP 1 LASTPIN (-4525 2225) BN 8
R 1
J 0
(-4532 2213);
DISPLAY 0.680851 (-4532 2213);
PAINT GREEN (-4532 2213);
FORCEPROP 1 LAST PATH I48
J 0
(-4527 2275);
DISPLAY 0.872340 (-4527 2275);
PAINT GREEN (-4527 2275);
DISPLAY INVISIBLE (-4527 2275);
FORCEPROP 2 LAST CDS_LIB mstr_standard
J 0
(-4525 2275);
PAINT MONO (-4525 2275);
DISPLAY INVISIBLE (-4525 2275);
FORCEPROP 1 LAST BODY_TYPE PLUMBING
J 0
(-4475 2225);
DISPLAY 2.276596 (-4475 2225);
PAINT GREEN (-4475 2225);
DISPLAY INVISIBLE (-4475 2225);
FORCEPROP 1 LAST HDL_TAP TRUE
J 0
(-4205 2145);
DISPLAY 2.276596 (-4205 2145);
PAINT GREEN (-4205 2145);
DISPLAY INVISIBLE (-4205 2145);
FORCEADD OFFPAGE..2
(-4325 2725);
FORCEPROP 2 LAST $XR0 108 
J 0
(-4136 2725);
DISPLAY 0.638298 (-4136 2725);
PAINT MONO (-4136 2725);
FORCEPROP 2 LAST PATH I49
J 0
(-4125 2775);
DISPLAY 1.021277 (-4125 2775);
PAINT ORANGE (-4125 2775);
DISPLAY INVISIBLE (-4125 2775);
FORCEPROP 2 LAST CDS_LIB mstr_standard
J 0
(-4325 2725);
PAINT MONO (-4325 2725);
DISPLAY INVISIBLE (-4325 2725);
FORCEPROP 1 LAST OFFPAGE TRUE
J 0
(-4000 2600);
DISPLAY 0.872340 (-4000 2600);
PAINT GREEN (-4000 2600);
DISPLAY INVISIBLE (-4000 2600);
FORCEPROP 1 LAST COMMENT_BODY TRUE
J 0
(-4370 2630);
DISPLAY 0.872340 (-4370 2630);
PAINT GREEN (-4370 2630);
DISPLAY INVISIBLE (-4370 2630);
FORCEADD CAP..1
R 2
(-5525 1725);
FORCEPROP 1 LAST TOLERANCE 10%
J 2
(-5575 1675);
DISPLAY 0.617021 (-5575 1675);
PAINT SKYBLUE (-5575 1675);
FORCEPROP 1 LAST VOLTAGE 16V
J 2
(-5575 1725);
DISPLAY 0.617021 (-5575 1725);
PAINT SKYBLUE (-5575 1725);
FORCEPROP 1 LAST MATERIAL X7R
J 2
(-5575 1625);
DISPLAY 0.617021 (-5575 1625);
PAINT SKYBLUE (-5575 1625);
FORCEPROP 1 LAST VALUE 0.22UF
J 2
(-5575 1775);
DISPLAY 0.617021 (-5575 1775);
PAINT SKYBLUE (-5575 1775);
FORCEPROP 1 LAST $LOCATION C829
J 2
(-5575 1825);
DISPLAY 0.617021 (-5575 1825);
PAINT AQUA (-5575 1825);
FORCEPROP 1 LASTPIN (-5525 1825) $PN 1
J 2
(-5535 1805);
DISPLAY 0.787234 (-5535 1805);
PAINT ORANGE (-5535 1805);
FORCEPROP 1 LASTPIN (-5525 1625) $PN 2
J 2
(-5535 1605);
DISPLAY 0.787234 (-5535 1605);
PAINT ORANGE (-5535 1605);
FORCEPROP 1 LAST PACK_TYPE 0402
J 2
(-5575 1525);
DISPLAY 0.617021 (-5575 1525);
PAINT SKYBLUE (-5575 1525);
FORCEPROP 1 LAST PART_NUMBER A36096-155
J 2
(-5575 1575);
DISPLAY 0.617021 (-5575 1575);
PAINT BLUE (-5575 1575);
FORCEPROP 0 LAST GROUP PCIE_RISER
J 0
(-5707 1503);
DISPLAY 0.638298 (-5707 1503);
PAINT BROWN (-5707 1503);
DISPLAY BOTH (-5707 1503);
FORCEPROP 1 LAST PATH I5
J 2
(-5575 1875);
DISPLAY 0.978723 (-5575 1875);
PAINT WHITE (-5575 1875);
DISPLAY INVISIBLE (-5575 1875);
FORCEPROP 2 LAST CDS_LOCATION C829
J 2
(-5575 1825);
DISPLAY 0.617021 (-5575 1825);
PAINT AQUA (-5575 1825);
DISPLAY INVISIBLE (-5575 1825);
FORCEPROP 2 LAST CDS_LIB mstr_discrete
J 0
(-5525 1725);
PAINT MONO (-5525 1725);
DISPLAY INVISIBLE (-5525 1725);
FORCEPROP 2 LAST ROOM OCP_STEERING
J 2
(-5525 1725);
PAINT MONO (-5525 1725);
DISPLAY INVISIBLE (-5525 1725);
FORCEPROP 0 LAST SEC 1
J 0
(-5575 1875);
PAINT MONO (-5575 1875);
DISPLAY INVISIBLE (-5575 1875);
FORCEPROP 2 LAST SEC_TYPE 0402
J 0
(-5575 1925);
DISPLAY 1.021277 (-5575 1925);
PAINT ORANGE (-5575 1925);
DISPLAY INVISIBLE (-5575 1925);
FORCEADD CAP..1
R 2
(-5025 3325);
FORCEPROP 1 LASTPIN (-5025 3225) $PN 2
J 2
(-5035 3205);
DISPLAY 0.787234 (-5035 3205);
PAINT ORANGE (-5035 3205);
FORCEPROP 1 LASTPIN (-5025 3425) $PN 1
J 2
(-5035 3405);
DISPLAY 0.787234 (-5035 3405);
PAINT ORANGE (-5035 3405);
FORCEPROP 1 LAST PACK_TYPE 0402
J 2
(-5075 3125);
DISPLAY 0.617021 (-5075 3125);
PAINT SKYBLUE (-5075 3125);
FORCEPROP 1 LAST TOLERANCE 10%
J 2
(-5075 3275);
DISPLAY 0.617021 (-5075 3275);
PAINT SKYBLUE (-5075 3275);
FORCEPROP 1 LAST MATERIAL X7R
J 2
(-5075 3225);
DISPLAY 0.617021 (-5075 3225);
PAINT SKYBLUE (-5075 3225);
FORCEPROP 1 LAST PART_NUMBER A36096-155
J 2
(-5075 3175);
DISPLAY 0.617021 (-5075 3175);
PAINT BLUE (-5075 3175);
FORCEPROP 1 LAST $LOCATION C834
J 2
(-5075 3425);
DISPLAY 0.617021 (-5075 3425);
PAINT AQUA (-5075 3425);
FORCEPROP 1 LAST VALUE 0.22UF
J 2
(-5075 3375);
DISPLAY 0.617021 (-5075 3375);
PAINT SKYBLUE (-5075 3375);
FORCEPROP 1 LAST VOLTAGE 16V
J 2
(-5075 3325);
DISPLAY 0.617021 (-5075 3325);
PAINT SKYBLUE (-5075 3325);
FORCEPROP 0 LAST GROUP PCIE_RISER
J 0
(-5182 3478);
DISPLAY 0.638298 (-5182 3478);
PAINT BROWN (-5182 3478);
DISPLAY BOTH (-5182 3478);
FORCEPROP 2 LAST SEC_TYPE 0402
J 0
(-5075 3525);
DISPLAY 1.021277 (-5075 3525);
PAINT ORANGE (-5075 3525);
DISPLAY INVISIBLE (-5075 3525);
FORCEPROP 0 LAST SEC 1
J 0
(-5075 3475);
PAINT MONO (-5075 3475);
DISPLAY INVISIBLE (-5075 3475);
FORCEPROP 1 LAST PATH I50
J 2
(-5075 3475);
DISPLAY 0.978723 (-5075 3475);
PAINT WHITE (-5075 3475);
DISPLAY INVISIBLE (-5075 3475);
FORCEPROP 2 LAST CDS_LOCATION C834
J 2
(-5075 3425);
DISPLAY 0.617021 (-5075 3425);
PAINT AQUA (-5075 3425);
DISPLAY INVISIBLE (-5075 3425);
FORCEPROP 2 LAST ROOM OCP_STEERING
J 2
(-5025 3325);
PAINT MONO (-5025 3325);
DISPLAY INVISIBLE (-5025 3325);
FORCEPROP 2 LAST CDS_LIB mstr_discrete
J 0
(-5025 3325);
PAINT MONO (-5025 3325);
DISPLAY INVISIBLE (-5025 3325);
FORCEADD CAP..1
R 2
(-4825 3025);
FORCEPROP 1 LASTPIN (-4825 2925) $PN 2
J 2
(-4835 2905);
DISPLAY 0.787234 (-4835 2905);
PAINT ORANGE (-4835 2905);
FORCEPROP 1 LASTPIN (-4825 3125) $PN 1
J 2
(-4835 3105);
DISPLAY 0.787234 (-4835 3105);
PAINT ORANGE (-4835 3105);
FORCEPROP 1 LAST PACK_TYPE 0402
J 2
(-4875 2825);
DISPLAY 0.617021 (-4875 2825);
PAINT SKYBLUE (-4875 2825);
FORCEPROP 1 LAST VALUE 0.22UF
J 2
(-4875 3075);
DISPLAY 0.617021 (-4875 3075);
PAINT SKYBLUE (-4875 3075);
FORCEPROP 1 LAST MATERIAL X7R
J 2
(-4875 2925);
DISPLAY 0.617021 (-4875 2925);
PAINT SKYBLUE (-4875 2925);
FORCEPROP 1 LAST TOLERANCE 10%
J 2
(-4875 2975);
DISPLAY 0.617021 (-4875 2975);
PAINT SKYBLUE (-4875 2975);
FORCEPROP 1 LAST $LOCATION C844
J 2
(-4875 3125);
DISPLAY 0.617021 (-4875 3125);
PAINT AQUA (-4875 3125);
FORCEPROP 1 LAST VOLTAGE 16V
J 2
(-4875 3025);
DISPLAY 0.617021 (-4875 3025);
PAINT SKYBLUE (-4875 3025);
FORCEPROP 1 LAST PART_NUMBER A36096-155
J 2
(-4875 2875);
DISPLAY 0.617021 (-4875 2875);
PAINT BLUE (-4875 2875);
FORCEPROP 0 LAST GROUP PCIE_RISER
J 0
(-5007 2803);
DISPLAY 0.638298 (-5007 2803);
PAINT BROWN (-5007 2803);
DISPLAY BOTH (-5007 2803);
FORCEPROP 2 LAST SEC_TYPE 0402
J 0
(-4875 3225);
DISPLAY 1.021277 (-4875 3225);
PAINT ORANGE (-4875 3225);
DISPLAY INVISIBLE (-4875 3225);
FORCEPROP 0 LAST SEC 1
J 0
(-4875 3175);
PAINT MONO (-4875 3175);
DISPLAY INVISIBLE (-4875 3175);
FORCEPROP 1 LAST PATH I51
J 2
(-4875 3175);
DISPLAY 0.978723 (-4875 3175);
PAINT WHITE (-4875 3175);
DISPLAY INVISIBLE (-4875 3175);
FORCEPROP 2 LAST CDS_LOCATION C844
J 2
(-4875 3125);
DISPLAY 0.617021 (-4875 3125);
PAINT AQUA (-4875 3125);
DISPLAY INVISIBLE (-4875 3125);
FORCEPROP 2 LAST ROOM OCP_STEERING
J 2
(-4825 3025);
PAINT MONO (-4825 3025);
DISPLAY INVISIBLE (-4825 3025);
FORCEPROP 2 LAST CDS_LIB mstr_discrete
J 0
(-4825 3025);
PAINT MONO (-4825 3025);
DISPLAY INVISIBLE (-4825 3025);
FORCEADD CAP..1
R 2
(-4625 3300);
FORCEPROP 1 LASTPIN (-4625 3200) $PN 2
J 2
(-4635 3180);
DISPLAY 0.787234 (-4635 3180);
PAINT ORANGE (-4635 3180);
FORCEPROP 1 LASTPIN (-4625 3400) $PN 1
J 2
(-4635 3380);
DISPLAY 0.787234 (-4635 3380);
PAINT ORANGE (-4635 3380);
FORCEPROP 1 LAST PACK_TYPE 0402
J 2
(-4675 3100);
DISPLAY 0.617021 (-4675 3100);
PAINT SKYBLUE (-4675 3100);
FORCEPROP 1 LAST VOLTAGE 16V
J 2
(-4675 3300);
DISPLAY 0.617021 (-4675 3300);
PAINT SKYBLUE (-4675 3300);
FORCEPROP 1 LAST VALUE 0.22UF
J 2
(-4675 3350);
DISPLAY 0.617021 (-4675 3350);
PAINT SKYBLUE (-4675 3350);
FORCEPROP 1 LAST TOLERANCE 10%
J 2
(-4675 3250);
DISPLAY 0.617021 (-4675 3250);
PAINT SKYBLUE (-4675 3250);
FORCEPROP 1 LAST MATERIAL X7R
J 2
(-4675 3200);
DISPLAY 0.617021 (-4675 3200);
PAINT SKYBLUE (-4675 3200);
FORCEPROP 1 LAST PART_NUMBER A36096-155
J 2
(-4675 3150);
DISPLAY 0.617021 (-4675 3150);
PAINT BLUE (-4675 3150);
FORCEPROP 1 LAST $LOCATION C842
J 2
(-4675 3400);
DISPLAY 0.617021 (-4675 3400);
PAINT AQUA (-4675 3400);
FORCEPROP 0 LAST GROUP PCIE_RISER
J 0
(-4607 3553);
DISPLAY 0.638298 (-4607 3553);
PAINT BROWN (-4607 3553);
DISPLAY BOTH (-4607 3553);
FORCEPROP 2 LAST SEC_TYPE 0402
J 0
(-4675 3500);
DISPLAY 1.021277 (-4675 3500);
PAINT ORANGE (-4675 3500);
DISPLAY INVISIBLE (-4675 3500);
FORCEPROP 0 LAST SEC 1
J 0
(-4675 3450);
PAINT MONO (-4675 3450);
DISPLAY INVISIBLE (-4675 3450);
FORCEPROP 1 LAST PATH I52
J 2
(-4675 3450);
DISPLAY 0.978723 (-4675 3450);
PAINT WHITE (-4675 3450);
DISPLAY INVISIBLE (-4675 3450);
FORCEPROP 2 LAST CDS_LOCATION C842
J 2
(-4675 3400);
DISPLAY 0.617021 (-4675 3400);
PAINT AQUA (-4675 3400);
DISPLAY INVISIBLE (-4675 3400);
FORCEPROP 2 LAST ROOM OCP_STEERING
J 2
(-4625 3300);
PAINT MONO (-4625 3300);
DISPLAY INVISIBLE (-4625 3300);
FORCEPROP 2 LAST CDS_LIB mstr_discrete
J 0
(-4625 3300);
PAINT MONO (-4625 3300);
DISPLAY INVISIBLE (-4625 3300);
FORCEADD TAP..3
(-5025 3575);
FORCEPROP 3 LASTPIN (-5025 3525) SIG_NAME P3E_CPU0_PE1_PCH_TXN<10>
J 0
(-5015 3535);
DISPLAY 0.659574 (-5015 3535);
PAINT MONO (-5015 3535);
DISPLAY INVISIBLE (-5015 3535);
FORCEPROP 1 LASTPIN (-5025 3525) BN 10
R 1
J 0
(-5032 3513);
DISPLAY 0.680851 (-5032 3513);
PAINT GREEN (-5032 3513);
FORCEPROP 1 LAST PATH I53
J 0
(-5027 3575);
DISPLAY 0.872340 (-5027 3575);
PAINT GREEN (-5027 3575);
DISPLAY INVISIBLE (-5027 3575);
FORCEPROP 2 LAST CDS_LIB mstr_standard
J 0
(-5025 3575);
PAINT MONO (-5025 3575);
DISPLAY INVISIBLE (-5025 3575);
FORCEPROP 1 LAST BODY_TYPE PLUMBING
J 0
(-4975 3525);
DISPLAY 2.276596 (-4975 3525);
PAINT GREEN (-4975 3525);
DISPLAY INVISIBLE (-4975 3525);
FORCEPROP 1 LAST HDL_TAP TRUE
J 0
(-4705 3445);
DISPLAY 2.276596 (-4705 3445);
PAINT GREEN (-4705 3445);
DISPLAY INVISIBLE (-4705 3445);
FORCEADD TAP..3
(-4825 3575);
FORCEPROP 3 LASTPIN (-4825 3525) SIG_NAME P3E_CPU0_PE1_PCH_TXN<9>
J 0
(-4815 3535);
DISPLAY 0.659574 (-4815 3535);
PAINT MONO (-4815 3535);
DISPLAY INVISIBLE (-4815 3535);
FORCEPROP 1 LASTPIN (-4825 3525) BN 9
R 1
J 0
(-4832 3513);
DISPLAY 0.680851 (-4832 3513);
PAINT GREEN (-4832 3513);
FORCEPROP 1 LAST PATH I54
J 0
(-4827 3575);
DISPLAY 0.872340 (-4827 3575);
PAINT GREEN (-4827 3575);
DISPLAY INVISIBLE (-4827 3575);
FORCEPROP 2 LAST CDS_LIB mstr_standard
J 0
(-4825 3575);
PAINT MONO (-4825 3575);
DISPLAY INVISIBLE (-4825 3575);
FORCEPROP 1 LAST BODY_TYPE PLUMBING
J 0
(-4775 3525);
DISPLAY 2.276596 (-4775 3525);
PAINT GREEN (-4775 3525);
DISPLAY INVISIBLE (-4775 3525);
FORCEPROP 1 LAST HDL_TAP TRUE
J 0
(-4505 3445);
DISPLAY 2.276596 (-4505 3445);
PAINT GREEN (-4505 3445);
DISPLAY INVISIBLE (-4505 3445);
FORCEADD TAP..3
(-4625 3575);
FORCEPROP 3 LASTPIN (-4625 3525) SIG_NAME P3E_CPU0_PE1_PCH_TXN<8>
J 0
(-4615 3535);
DISPLAY 0.659574 (-4615 3535);
PAINT MONO (-4615 3535);
DISPLAY INVISIBLE (-4615 3535);
FORCEPROP 1 LASTPIN (-4625 3525) BN 8
R 1
J 0
(-4632 3513);
DISPLAY 0.680851 (-4632 3513);
PAINT GREEN (-4632 3513);
FORCEPROP 1 LAST PATH I55
J 0
(-4627 3575);
DISPLAY 0.872340 (-4627 3575);
PAINT GREEN (-4627 3575);
DISPLAY INVISIBLE (-4627 3575);
FORCEPROP 2 LAST CDS_LIB mstr_standard
J 0
(-4625 3575);
PAINT MONO (-4625 3575);
DISPLAY INVISIBLE (-4625 3575);
FORCEPROP 1 LAST BODY_TYPE PLUMBING
J 0
(-4575 3525);
DISPLAY 2.276596 (-4575 3525);
PAINT GREEN (-4575 3525);
DISPLAY INVISIBLE (-4575 3525);
FORCEPROP 1 LAST HDL_TAP TRUE
J 0
(-4305 3445);
DISPLAY 2.276596 (-4305 3445);
PAINT GREEN (-4305 3445);
DISPLAY INVISIBLE (-4305 3445);
FORCEADD OFFPAGE..1
(-3600 2325);
FORCEPROP 2 LAST $XR1 30 
J 0
(-3942 2325);
DISPLAY 0.638298 (-3942 2325);
PAINT MONO (-3942 2325);
FORCEPROP 2 LAST $XR0 105 
J 0
(-3852 2325);
DISPLAY 0.638298 (-3852 2325);
PAINT MONO (-3852 2325);
FORCEPROP 2 LAST PATH I56
J 0
(-3850 2375);
DISPLAY 1.021277 (-3850 2375);
PAINT ORANGE (-3850 2375);
DISPLAY INVISIBLE (-3850 2375);
FORCEPROP 2 LAST CDS_LIB mstr_standard
J 0
(-3600 2325);
PAINT MONO (-3600 2325);
DISPLAY INVISIBLE (-3600 2325);
FORCEPROP 1 LAST OFFPAGE TRUE
J 0
(-3280 2195);
PAINT GREEN (-3280 2195);
DISPLAY INVISIBLE (-3280 2195);
FORCEPROP 1 LAST COMMENT_BODY TRUE
J 0
(-3480 2225);
DISPLAY 2.276596 (-3480 2225);
PAINT GREEN (-3480 2225);
DISPLAY INVISIBLE (-3480 2225);
FORCEADD TAP..3
(-3425 2275);
FORCEPROP 3 LASTPIN (-3425 2225) SIG_NAME P3E_CPU0_PE1_PCH_RXP<15>
J 0
(-3415 2235);
DISPLAY 0.659574 (-3415 2235);
PAINT MONO (-3415 2235);
DISPLAY INVISIBLE (-3415 2235);
FORCEPROP 1 LASTPIN (-3425 2225) BN 15
R 1
J 0
(-3432 2213);
DISPLAY 0.680851 (-3432 2213);
PAINT GREEN (-3432 2213);
FORCEPROP 1 LAST PATH I57
J 0
(-3427 2275);
DISPLAY 0.872340 (-3427 2275);
PAINT GREEN (-3427 2275);
DISPLAY INVISIBLE (-3427 2275);
FORCEPROP 2 LAST CDS_LIB mstr_standard
J 0
(-3425 2275);
PAINT MONO (-3425 2275);
DISPLAY INVISIBLE (-3425 2275);
FORCEPROP 1 LAST BODY_TYPE PLUMBING
J 0
(-3375 2225);
DISPLAY 2.276596 (-3375 2225);
PAINT GREEN (-3375 2225);
DISPLAY INVISIBLE (-3375 2225);
FORCEPROP 1 LAST HDL_TAP TRUE
J 0
(-3105 2145);
DISPLAY 2.276596 (-3105 2145);
PAINT GREEN (-3105 2145);
DISPLAY INVISIBLE (-3105 2145);
FORCEADD RES..2
(-3225 2075);
FORCEPROP 0 LAST GROUP PCIE_RISER
J 0
(-3207 2253);
DISPLAY 0.638298 (-3207 2253);
PAINT BROWN (-3207 2253);
DISPLAY BOTH (-3207 2253);
FORCEPROP 1 LAST PART_NUMBER G21497-005
J 0
(-3185 1950);
DISPLAY 0.617021 (-3185 1950);
PAINT BLUE (-3185 1950);
FORCEPROP 1 LAST VALUE 0.0
J 0
(-3180 2150);
DISPLAY 0.617021 (-3180 2150);
PAINT SKYBLUE (-3180 2150);
FORCEPROP 1 LAST TOLERANCE 5%
J 0
(-3180 2100);
DISPLAY 0.617021 (-3180 2100);
PAINT SKYBLUE (-3180 2100);
FORCEPROP 1 LAST MATERIAL CHIP
J 0
(-3185 2000);
DISPLAY 0.617021 (-3185 2000);
PAINT SKYBLUE (-3185 2000);
FORCEPROP 1 LASTPIN (-3225 1975) $PN 2
J 0
(-3220 1985);
DISPLAY 0.787234 (-3220 1985);
PAINT ORANGE (-3220 1985);
FORCEPROP 1 LASTPIN (-3225 2175) $PN 1
J 0
(-3220 2137);
DISPLAY 0.787234 (-3220 2137);
PAINT ORANGE (-3220 2137);
FORCEPROP 1 LAST PACK_TYPE 0402
J 0
(-3160 1900);
DISPLAY 0.617021 (-3160 1900);
PAINT SKYBLUE (-3160 1900);
FORCEPROP 1 LAST $LOCATION R769
J 0
(-3180 2200);
DISPLAY 0.617021 (-3180 2200);
PAINT AQUA (-3180 2200);
FORCEPROP 1 LAST WATTAGE 1/16W
J 0
(-3185 2050);
DISPLAY 0.617021 (-3185 2050);
PAINT SKYBLUE (-3185 2050);
FORCEPROP 1 LAST PATH I58
J 0
(-3175 2250);
DISPLAY 0.978723 (-3175 2250);
PAINT WHITE (-3175 2250);
DISPLAY INVISIBLE (-3175 2250);
FORCEPROP 0 LAST CDS_LOCATION R769
J 0
(-3175 2250);
PAINT MONO (-3175 2250);
DISPLAY INVISIBLE (-3175 2250);
FORCEPROP 2 LAST CDS_LIB mstr_discrete
J 0
(-3225 2075);
PAINT MONO (-3225 2075);
DISPLAY INVISIBLE (-3225 2075);
FORCEPROP 2 LAST ROOM PCIE_STEERING
J 0
(-3175 2250);
PAINT MONO (-3175 2250);
DISPLAY INVISIBLE (-3175 2250);
FORCEPROP 2 LAST SEC_TYPE 0402
J 0
(-3175 2300);
DISPLAY 1.021277 (-3175 2300);
PAINT ORANGE (-3175 2300);
DISPLAY INVISIBLE (-3175 2300);
FORCEPROP 0 LAST SEC 1
J 0
(-3175 2250);
PAINT MONO (-3175 2250);
DISPLAY INVISIBLE (-3175 2250);
FORCEADD TAP..3
(-3225 2275);
FORCEPROP 3 LASTPIN (-3225 2225) SIG_NAME P3E_CPU0_PE1_PCH_RXP<14>
J 0
(-3215 2235);
DISPLAY 0.659574 (-3215 2235);
PAINT MONO (-3215 2235);
DISPLAY INVISIBLE (-3215 2235);
FORCEPROP 1 LASTPIN (-3225 2225) BN 14
R 1
J 0
(-3232 2213);
DISPLAY 0.680851 (-3232 2213);
PAINT GREEN (-3232 2213);
FORCEPROP 1 LAST PATH I59
J 0
(-3227 2275);
DISPLAY 0.872340 (-3227 2275);
PAINT GREEN (-3227 2275);
DISPLAY INVISIBLE (-3227 2275);
FORCEPROP 2 LAST CDS_LIB mstr_standard
J 0
(-3225 2275);
PAINT MONO (-3225 2275);
DISPLAY INVISIBLE (-3225 2275);
FORCEPROP 1 LAST BODY_TYPE PLUMBING
J 0
(-3175 2225);
DISPLAY 2.276596 (-3175 2225);
PAINT GREEN (-3175 2225);
DISPLAY INVISIBLE (-3175 2225);
FORCEPROP 1 LAST HDL_TAP TRUE
J 0
(-2905 2145);
DISPLAY 2.276596 (-2905 2145);
PAINT GREEN (-2905 2145);
DISPLAY INVISIBLE (-2905 2145);
FORCEADD TAP..7
(-5325 1475);
FORCEPROP 3 LASTPIN (-5325 1525) SIG_NAME P3E_CPU0_PE1_PCH_CON_TXP<12>
J 0
(-5315 1535);
DISPLAY 0.659574 (-5315 1535);
PAINT MONO (-5315 1535);
DISPLAY INVISIBLE (-5315 1535);
FORCEPROP 1 LASTPIN (-5325 1525) BN 12
R 1
J 0
(-5332 1473);
DISPLAY 0.680851 (-5332 1473);
PAINT GREEN (-5332 1473);
FORCEPROP 1 LAST PATH I6
J 0
(-5327 1475);
DISPLAY 0.872340 (-5327 1475);
PAINT GREEN (-5327 1475);
DISPLAY INVISIBLE (-5327 1475);
FORCEPROP 2 LAST CDS_LIB mstr_standard
J 0
(-5325 1475);
PAINT MONO (-5325 1475);
DISPLAY INVISIBLE (-5325 1475);
FORCEPROP 1 LAST BODY_TYPE PLUMBING
J 0
(-5275 1475);
DISPLAY 2.276596 (-5275 1475);
PAINT GREEN (-5275 1475);
DISPLAY INVISIBLE (-5275 1475);
FORCEPROP 1 LAST HDL_TAP TRUE
J 0
(-5005 1345);
DISPLAY 2.276596 (-5005 1345);
PAINT GREEN (-5005 1345);
DISPLAY INVISIBLE (-5005 1345);
FORCEADD TAP..7
(-3500 2775);
FORCEPROP 3 LASTPIN (-3500 2825) SIG_NAME P3E_CPU0_PE1_PCH_CON_RXN<15>
J 0
(-3490 2835);
DISPLAY 0.659574 (-3490 2835);
PAINT MONO (-3490 2835);
DISPLAY INVISIBLE (-3490 2835);
FORCEPROP 1 LASTPIN (-3500 2825) BN 15
R 1
J 0
(-3507 2773);
DISPLAY 0.680851 (-3507 2773);
PAINT GREEN (-3507 2773);
FORCEPROP 1 LAST PATH I60
J 0
(-3502 2775);
DISPLAY 0.872340 (-3502 2775);
PAINT GREEN (-3502 2775);
DISPLAY INVISIBLE (-3502 2775);
FORCEPROP 2 LAST CDS_LIB mstr_standard
J 0
(-3500 2775);
PAINT MONO (-3500 2775);
DISPLAY INVISIBLE (-3500 2775);
FORCEPROP 1 LAST BODY_TYPE PLUMBING
J 0
(-3450 2775);
DISPLAY 2.276596 (-3450 2775);
PAINT GREEN (-3450 2775);
DISPLAY INVISIBLE (-3450 2775);
FORCEPROP 1 LAST HDL_TAP TRUE
J 0
(-3180 2645);
DISPLAY 2.276596 (-3180 2645);
PAINT GREEN (-3180 2645);
DISPLAY INVISIBLE (-3180 2645);
FORCEADD TAP..7
(-3300 2775);
FORCEPROP 3 LASTPIN (-3300 2825) SIG_NAME P3E_CPU0_PE1_PCH_CON_RXN<14>
J 0
(-3290 2835);
DISPLAY 0.659574 (-3290 2835);
PAINT MONO (-3290 2835);
DISPLAY INVISIBLE (-3290 2835);
FORCEPROP 1 LASTPIN (-3300 2825) BN 14
R 1
J 0
(-3307 2773);
DISPLAY 0.680851 (-3307 2773);
PAINT GREEN (-3307 2773);
FORCEPROP 1 LAST PATH I61
J 0
(-3302 2775);
DISPLAY 0.872340 (-3302 2775);
PAINT GREEN (-3302 2775);
DISPLAY INVISIBLE (-3302 2775);
FORCEPROP 2 LAST CDS_LIB mstr_standard
J 0
(-3300 2775);
PAINT MONO (-3300 2775);
DISPLAY INVISIBLE (-3300 2775);
FORCEPROP 1 LAST BODY_TYPE PLUMBING
J 0
(-3250 2775);
DISPLAY 2.276596 (-3250 2775);
PAINT GREEN (-3250 2775);
DISPLAY INVISIBLE (-3250 2775);
FORCEPROP 1 LAST HDL_TAP TRUE
J 0
(-2980 2645);
DISPLAY 2.276596 (-2980 2645);
PAINT GREEN (-2980 2645);
DISPLAY INVISIBLE (-2980 2645);
FORCEADD TAP..7
(-3100 2775);
FORCEPROP 3 LASTPIN (-3100 2825) SIG_NAME P3E_CPU0_PE1_PCH_CON_RXN<13>
J 0
(-3090 2835);
DISPLAY 0.659574 (-3090 2835);
PAINT MONO (-3090 2835);
DISPLAY INVISIBLE (-3090 2835);
FORCEPROP 1 LASTPIN (-3100 2825) BN 13
R 1
J 0
(-3107 2773);
DISPLAY 0.680851 (-3107 2773);
PAINT GREEN (-3107 2773);
FORCEPROP 1 LAST PATH I62
J 0
(-3102 2775);
DISPLAY 0.872340 (-3102 2775);
PAINT GREEN (-3102 2775);
DISPLAY INVISIBLE (-3102 2775);
FORCEPROP 2 LAST CDS_LIB mstr_standard
J 0
(-3100 2775);
PAINT MONO (-3100 2775);
DISPLAY INVISIBLE (-3100 2775);
FORCEPROP 1 LAST BODY_TYPE PLUMBING
J 0
(-3050 2775);
DISPLAY 2.276596 (-3050 2775);
PAINT GREEN (-3050 2775);
DISPLAY INVISIBLE (-3050 2775);
FORCEPROP 1 LAST HDL_TAP TRUE
J 0
(-2780 2645);
DISPLAY 2.276596 (-2780 2645);
PAINT GREEN (-2780 2645);
DISPLAY INVISIBLE (-2780 2645);
FORCEADD OFFPAGE..1
(-3675 3625);
FORCEPROP 2 LAST $XR1 30 
J 0
(-4047 3625);
DISPLAY 0.638298 (-4047 3625);
PAINT MONO (-4047 3625);
FORCEPROP 2 LAST $XR0 105 
J 0
(-3957 3625);
DISPLAY 0.638298 (-3957 3625);
PAINT MONO (-3957 3625);
FORCEPROP 2 LAST PATH I63
J 0
(-3925 3675);
DISPLAY 1.021277 (-3925 3675);
PAINT ORANGE (-3925 3675);
DISPLAY INVISIBLE (-3925 3675);
FORCEPROP 2 LAST CDS_LIB mstr_standard
J 0
(-3675 3625);
PAINT MONO (-3675 3625);
DISPLAY INVISIBLE (-3675 3625);
FORCEPROP 1 LAST OFFPAGE TRUE
J 0
(-3355 3495);
PAINT GREEN (-3355 3495);
DISPLAY INVISIBLE (-3355 3495);
FORCEPROP 1 LAST COMMENT_BODY TRUE
J 0
(-3555 3525);
DISPLAY 2.276596 (-3555 3525);
PAINT GREEN (-3555 3525);
DISPLAY INVISIBLE (-3555 3525);
FORCEADD RES..2
(-3500 3025);
FORCEPROP 0 LAST GROUP PCIE_RISER
J 0
(-3482 2828);
DISPLAY 0.638298 (-3482 2828);
PAINT BROWN (-3482 2828);
DISPLAY BOTH (-3482 2828);
FORCEPROP 1 LAST PART_NUMBER G21497-005
J 0
(-3460 2900);
DISPLAY 0.617021 (-3460 2900);
PAINT BLUE (-3460 2900);
FORCEPROP 1 LAST MATERIAL CHIP
J 0
(-3460 2950);
DISPLAY 0.617021 (-3460 2950);
PAINT SKYBLUE (-3460 2950);
FORCEPROP 1 LAST WATTAGE 1/16W
J 0
(-3460 3000);
DISPLAY 0.617021 (-3460 3000);
PAINT SKYBLUE (-3460 3000);
FORCEPROP 1 LAST $LOCATION R760
J 0
(-3455 3150);
DISPLAY 0.617021 (-3455 3150);
PAINT AQUA (-3455 3150);
FORCEPROP 1 LAST VALUE 0.0
J 0
(-3455 3100);
DISPLAY 0.617021 (-3455 3100);
PAINT SKYBLUE (-3455 3100);
FORCEPROP 1 LAST TOLERANCE 5%
J 0
(-3455 3050);
DISPLAY 0.617021 (-3455 3050);
PAINT SKYBLUE (-3455 3050);
FORCEPROP 1 LASTPIN (-3500 3125) $PN 1
J 0
(-3495 3087);
DISPLAY 0.787234 (-3495 3087);
PAINT ORANGE (-3495 3087);
FORCEPROP 1 LAST PACK_TYPE 0402
J 0
(-3435 2850);
DISPLAY 0.617021 (-3435 2850);
PAINT SKYBLUE (-3435 2850);
FORCEPROP 1 LASTPIN (-3500 2925) $PN 2
J 0
(-3495 2935);
DISPLAY 0.787234 (-3495 2935);
PAINT ORANGE (-3495 2935);
FORCEPROP 2 LAST SEC_TYPE 0402
J 0
(-3450 3250);
DISPLAY 1.021277 (-3450 3250);
PAINT ORANGE (-3450 3250);
DISPLAY INVISIBLE (-3450 3250);
FORCEPROP 0 LAST SEC 1
J 0
(-3450 3200);
PAINT MONO (-3450 3200);
DISPLAY INVISIBLE (-3450 3200);
FORCEPROP 1 LAST PATH I64
J 0
(-3450 3200);
DISPLAY 0.978723 (-3450 3200);
PAINT WHITE (-3450 3200);
DISPLAY INVISIBLE (-3450 3200);
FORCEPROP 0 LAST CDS_LOCATION R760
J 0
(-3450 3200);
PAINT MONO (-3450 3200);
DISPLAY INVISIBLE (-3450 3200);
FORCEPROP 2 LAST CDS_LIB mstr_discrete
J 0
(-3500 3025);
PAINT MONO (-3500 3025);
DISPLAY INVISIBLE (-3500 3025);
FORCEPROP 2 LAST ROOM PCIE_STEERING
J 0
(-3450 3200);
PAINT MONO (-3450 3200);
DISPLAY INVISIBLE (-3450 3200);
FORCEADD RES..2
(-3100 3025);
FORCEPROP 1 LAST TOLERANCE 5%
J 0
(-3055 3050);
DISPLAY 0.617021 (-3055 3050);
PAINT SKYBLUE (-3055 3050);
FORCEPROP 1 LAST WATTAGE 1/16W
J 0
(-3060 3000);
DISPLAY 0.617021 (-3060 3000);
PAINT SKYBLUE (-3060 3000);
FORCEPROP 1 LAST PART_NUMBER G21497-005
J 0
(-3060 2900);
DISPLAY 0.617021 (-3060 2900);
PAINT BLUE (-3060 2900);
FORCEPROP 1 LAST PACK_TYPE 0402
J 0
(-3035 2850);
DISPLAY 0.617021 (-3035 2850);
PAINT SKYBLUE (-3035 2850);
FORCEPROP 1 LAST MATERIAL CHIP
J 0
(-3060 2950);
DISPLAY 0.617021 (-3060 2950);
PAINT SKYBLUE (-3060 2950);
FORCEPROP 1 LASTPIN (-3100 2925) $PN 2
J 0
(-3095 2935);
DISPLAY 0.787234 (-3095 2935);
PAINT ORANGE (-3095 2935);
FORCEPROP 1 LASTPIN (-3100 3125) $PN 1
J 0
(-3095 3087);
DISPLAY 0.787234 (-3095 3087);
PAINT ORANGE (-3095 3087);
FORCEPROP 1 LAST $LOCATION R771
J 0
(-3055 3150);
DISPLAY 0.617021 (-3055 3150);
PAINT AQUA (-3055 3150);
FORCEPROP 1 LAST VALUE 0.0
J 0
(-3055 3100);
DISPLAY 0.617021 (-3055 3100);
PAINT SKYBLUE (-3055 3100);
FORCEPROP 0 LAST GROUP PCIE_RISER
J 0
(-3082 2828);
DISPLAY 0.638298 (-3082 2828);
PAINT BROWN (-3082 2828);
DISPLAY BOTH (-3082 2828);
FORCEPROP 2 LAST SEC_TYPE 0402
J 0
(-3050 3250);
DISPLAY 1.021277 (-3050 3250);
PAINT ORANGE (-3050 3250);
DISPLAY INVISIBLE (-3050 3250);
FORCEPROP 0 LAST SEC 1
J 0
(-3050 3200);
PAINT MONO (-3050 3200);
DISPLAY INVISIBLE (-3050 3200);
FORCEPROP 1 LAST PATH I65
J 0
(-3050 3200);
DISPLAY 0.978723 (-3050 3200);
PAINT WHITE (-3050 3200);
DISPLAY INVISIBLE (-3050 3200);
FORCEPROP 0 LAST CDS_LOCATION R771
J 0
(-3050 3200);
PAINT MONO (-3050 3200);
DISPLAY INVISIBLE (-3050 3200);
FORCEPROP 2 LAST CDS_LIB mstr_discrete
J 0
(-3100 3025);
PAINT MONO (-3100 3025);
DISPLAY INVISIBLE (-3100 3025);
FORCEPROP 2 LAST ROOM PCIE_STEERING
J 0
(-3050 3200);
PAINT MONO (-3050 3200);
DISPLAY INVISIBLE (-3050 3200);
FORCEADD RES..2
(-3300 3375);
FORCEPROP 1 LAST MATERIAL CHIP
J 0
(-3260 3300);
DISPLAY 0.617021 (-3260 3300);
PAINT SKYBLUE (-3260 3300);
FORCEPROP 1 LASTPIN (-3300 3275) $PN 2
J 0
(-3295 3285);
DISPLAY 0.787234 (-3295 3285);
PAINT ORANGE (-3295 3285);
FORCEPROP 1 LASTPIN (-3300 3475) $PN 1
J 0
(-3295 3437);
DISPLAY 0.787234 (-3295 3437);
PAINT ORANGE (-3295 3437);
FORCEPROP 1 LAST TOLERANCE 5%
J 0
(-3255 3400);
DISPLAY 0.617021 (-3255 3400);
PAINT SKYBLUE (-3255 3400);
FORCEPROP 1 LAST PACK_TYPE 0402
J 0
(-3235 3200);
DISPLAY 0.617021 (-3235 3200);
PAINT SKYBLUE (-3235 3200);
FORCEPROP 0 LAST GROUP PCIE_RISER
J 0
(-3282 3578);
DISPLAY 0.638298 (-3282 3578);
PAINT BROWN (-3282 3578);
DISPLAY BOTH (-3282 3578);
FORCEPROP 1 LAST $LOCATION R768
J 0
(-3255 3500);
DISPLAY 0.617021 (-3255 3500);
PAINT AQUA (-3255 3500);
FORCEPROP 1 LAST VALUE 0.0
J 0
(-3255 3450);
DISPLAY 0.617021 (-3255 3450);
PAINT SKYBLUE (-3255 3450);
FORCEPROP 1 LAST WATTAGE 1/16W
J 0
(-3260 3350);
DISPLAY 0.617021 (-3260 3350);
PAINT SKYBLUE (-3260 3350);
FORCEPROP 1 LAST PART_NUMBER G21497-005
J 0
(-3260 3250);
DISPLAY 0.617021 (-3260 3250);
PAINT BLUE (-3260 3250);
FORCEPROP 0 LAST SEC 1
J 0
(-3250 3550);
PAINT MONO (-3250 3550);
DISPLAY INVISIBLE (-3250 3550);
FORCEPROP 2 LAST SEC_TYPE 0402
J 0
(-3250 3600);
DISPLAY 1.021277 (-3250 3600);
PAINT ORANGE (-3250 3600);
DISPLAY INVISIBLE (-3250 3600);
FORCEPROP 2 LAST ROOM PCIE_STEERING
J 0
(-3250 3550);
PAINT MONO (-3250 3550);
DISPLAY INVISIBLE (-3250 3550);
FORCEPROP 2 LAST CDS_LIB mstr_discrete
J 0
(-3300 3375);
PAINT MONO (-3300 3375);
DISPLAY INVISIBLE (-3300 3375);
FORCEPROP 0 LAST CDS_LOCATION R768
J 0
(-3250 3550);
PAINT MONO (-3250 3550);
DISPLAY INVISIBLE (-3250 3550);
FORCEPROP 1 LAST PATH I66
J 0
(-3250 3550);
DISPLAY 0.978723 (-3250 3550);
PAINT WHITE (-3250 3550);
DISPLAY INVISIBLE (-3250 3550);
FORCEADD TAP..3
(-3500 3575);
FORCEPROP 3 LASTPIN (-3500 3525) SIG_NAME P3E_CPU0_PE1_PCH_RXN<15>
J 0
(-3490 3535);
DISPLAY 0.659574 (-3490 3535);
PAINT MONO (-3490 3535);
DISPLAY INVISIBLE (-3490 3535);
FORCEPROP 1 LASTPIN (-3500 3525) BN 15
R 1
J 0
(-3507 3513);
DISPLAY 0.680851 (-3507 3513);
PAINT GREEN (-3507 3513);
FORCEPROP 1 LAST PATH I67
J 0
(-3502 3575);
DISPLAY 0.872340 (-3502 3575);
PAINT GREEN (-3502 3575);
DISPLAY INVISIBLE (-3502 3575);
FORCEPROP 2 LAST CDS_LIB mstr_standard
J 0
(-3500 3575);
PAINT MONO (-3500 3575);
DISPLAY INVISIBLE (-3500 3575);
FORCEPROP 1 LAST BODY_TYPE PLUMBING
J 0
(-3450 3525);
DISPLAY 2.276596 (-3450 3525);
PAINT GREEN (-3450 3525);
DISPLAY INVISIBLE (-3450 3525);
FORCEPROP 1 LAST HDL_TAP TRUE
J 0
(-3180 3445);
DISPLAY 2.276596 (-3180 3445);
PAINT GREEN (-3180 3445);
DISPLAY INVISIBLE (-3180 3445);
FORCEADD TAP..3
(-3300 3575);
FORCEPROP 3 LASTPIN (-3300 3525) SIG_NAME P3E_CPU0_PE1_PCH_RXN<14>
J 0
(-3290 3535);
DISPLAY 0.659574 (-3290 3535);
PAINT MONO (-3290 3535);
DISPLAY INVISIBLE (-3290 3535);
FORCEPROP 1 LASTPIN (-3300 3525) BN 14
R 1
J 0
(-3307 3513);
DISPLAY 0.680851 (-3307 3513);
PAINT GREEN (-3307 3513);
FORCEPROP 1 LAST PATH I68
J 0
(-3302 3575);
DISPLAY 0.872340 (-3302 3575);
PAINT GREEN (-3302 3575);
DISPLAY INVISIBLE (-3302 3575);
FORCEPROP 2 LAST CDS_LIB mstr_standard
J 0
(-3300 3575);
PAINT MONO (-3300 3575);
DISPLAY INVISIBLE (-3300 3575);
FORCEPROP 1 LAST BODY_TYPE PLUMBING
J 0
(-3250 3525);
DISPLAY 2.276596 (-3250 3525);
PAINT GREEN (-3250 3525);
DISPLAY INVISIBLE (-3250 3525);
FORCEPROP 1 LAST HDL_TAP TRUE
J 0
(-2980 3445);
DISPLAY 2.276596 (-2980 3445);
PAINT GREEN (-2980 3445);
DISPLAY INVISIBLE (-2980 3445);
FORCEADD TAP..3
(-3100 3575);
FORCEPROP 3 LASTPIN (-3100 3525) SIG_NAME P3E_CPU0_PE1_PCH_RXN<13>
J 0
(-3090 3535);
DISPLAY 0.659574 (-3090 3535);
PAINT MONO (-3090 3535);
DISPLAY INVISIBLE (-3090 3535);
FORCEPROP 1 LASTPIN (-3100 3525) BN 13
R 1
J 0
(-3107 3513);
DISPLAY 0.680851 (-3107 3513);
PAINT GREEN (-3107 3513);
FORCEPROP 1 LAST PATH I69
J 0
(-3102 3575);
DISPLAY 0.872340 (-3102 3575);
PAINT GREEN (-3102 3575);
DISPLAY INVISIBLE (-3102 3575);
FORCEPROP 2 LAST CDS_LIB mstr_standard
J 0
(-3100 3575);
PAINT MONO (-3100 3575);
DISPLAY INVISIBLE (-3100 3575);
FORCEPROP 1 LAST BODY_TYPE PLUMBING
J 0
(-3050 3525);
DISPLAY 2.276596 (-3050 3525);
PAINT GREEN (-3050 3525);
DISPLAY INVISIBLE (-3050 3525);
FORCEPROP 1 LAST HDL_TAP TRUE
J 0
(-2780 3445);
DISPLAY 2.276596 (-2780 3445);
PAINT GREEN (-2780 3445);
DISPLAY INVISIBLE (-2780 3445);
FORCEADD TAP..7
(-5125 1475);
FORCEPROP 3 LASTPIN (-5125 1525) SIG_NAME P3E_CPU0_PE1_PCH_CON_TXP<11>
J 0
(-5115 1535);
DISPLAY 0.659574 (-5115 1535);
PAINT MONO (-5115 1535);
DISPLAY INVISIBLE (-5115 1535);
FORCEPROP 1 LASTPIN (-5125 1525) BN 11
R 1
J 0
(-5132 1473);
DISPLAY 0.680851 (-5132 1473);
PAINT GREEN (-5132 1473);
FORCEPROP 1 LAST PATH I7
J 0
(-5127 1475);
DISPLAY 0.872340 (-5127 1475);
PAINT GREEN (-5127 1475);
DISPLAY INVISIBLE (-5127 1475);
FORCEPROP 2 LAST CDS_LIB mstr_standard
J 0
(-5125 1475);
PAINT MONO (-5125 1475);
DISPLAY INVISIBLE (-5125 1475);
FORCEPROP 1 LAST BODY_TYPE PLUMBING
J 0
(-5075 1475);
DISPLAY 2.276596 (-5075 1475);
PAINT GREEN (-5075 1475);
DISPLAY INVISIBLE (-5075 1475);
FORCEPROP 1 LAST HDL_TAP TRUE
J 0
(-4805 1345);
DISPLAY 2.276596 (-4805 1345);
PAINT GREEN (-4805 1345);
DISPLAY INVISIBLE (-4805 1345);
FORCEADD TAP..7
(-3025 1475);
FORCEPROP 3 LASTPIN (-3025 1525) SIG_NAME P3E_CPU0_PE1_PCH_CON_RXP<13>
J 0
(-3015 1535);
DISPLAY 0.659574 (-3015 1535);
PAINT MONO (-3015 1535);
DISPLAY INVISIBLE (-3015 1535);
FORCEPROP 1 LASTPIN (-3025 1525) BN 13
R 1
J 0
(-3032 1473);
DISPLAY 0.680851 (-3032 1473);
PAINT GREEN (-3032 1473);
FORCEPROP 1 LAST PATH I70
J 0
(-3027 1475);
DISPLAY 0.872340 (-3027 1475);
PAINT GREEN (-3027 1475);
DISPLAY INVISIBLE (-3027 1475);
FORCEPROP 2 LAST CDS_LIB mstr_standard
J 0
(-3025 1475);
PAINT MONO (-3025 1475);
DISPLAY INVISIBLE (-3025 1475);
FORCEPROP 1 LAST BODY_TYPE PLUMBING
J 0
(-2975 1475);
DISPLAY 2.276596 (-2975 1475);
PAINT GREEN (-2975 1475);
DISPLAY INVISIBLE (-2975 1475);
FORCEPROP 1 LAST HDL_TAP TRUE
J 0
(-2705 1345);
DISPLAY 2.276596 (-2705 1345);
PAINT GREEN (-2705 1345);
DISPLAY INVISIBLE (-2705 1345);
FORCEADD TAP..7
(-2825 1475);
FORCEPROP 3 LASTPIN (-2825 1525) SIG_NAME P3E_CPU0_PE1_PCH_CON_RXP<12>
J 0
(-2815 1535);
DISPLAY 0.659574 (-2815 1535);
PAINT MONO (-2815 1535);
DISPLAY INVISIBLE (-2815 1535);
FORCEPROP 1 LASTPIN (-2825 1525) BN 12
R 1
J 0
(-2832 1473);
DISPLAY 0.680851 (-2832 1473);
PAINT GREEN (-2832 1473);
FORCEPROP 1 LAST PATH I71
J 0
(-2827 1475);
DISPLAY 0.872340 (-2827 1475);
PAINT GREEN (-2827 1475);
DISPLAY INVISIBLE (-2827 1475);
FORCEPROP 2 LAST CDS_LIB mstr_standard
J 0
(-2825 1475);
PAINT MONO (-2825 1475);
DISPLAY INVISIBLE (-2825 1475);
FORCEPROP 1 LAST BODY_TYPE PLUMBING
J 0
(-2775 1475);
DISPLAY 2.276596 (-2775 1475);
PAINT GREEN (-2775 1475);
DISPLAY INVISIBLE (-2775 1475);
FORCEPROP 1 LAST HDL_TAP TRUE
J 0
(-2505 1345);
DISPLAY 2.276596 (-2505 1345);
PAINT GREEN (-2505 1345);
DISPLAY INVISIBLE (-2505 1345);
FORCEADD RES..2
(-3025 1725);
FORCEPROP 1 LAST $LOCATION R774
J 0
(-2980 1850);
DISPLAY 0.617021 (-2980 1850);
PAINT AQUA (-2980 1850);
FORCEPROP 1 LAST TOLERANCE 5%
J 0
(-2980 1750);
DISPLAY 0.617021 (-2980 1750);
PAINT SKYBLUE (-2980 1750);
FORCEPROP 1 LASTPIN (-3025 1625) $PN 2
J 0
(-3020 1635);
DISPLAY 0.787234 (-3020 1635);
PAINT ORANGE (-3020 1635);
FORCEPROP 1 LASTPIN (-3025 1825) $PN 1
J 0
(-3020 1787);
DISPLAY 0.787234 (-3020 1787);
PAINT ORANGE (-3020 1787);
FORCEPROP 1 LAST VALUE 0.0
J 0
(-2980 1800);
DISPLAY 0.617021 (-2980 1800);
PAINT SKYBLUE (-2980 1800);
FORCEPROP 1 LAST PACK_TYPE 0402
J 0
(-2960 1550);
DISPLAY 0.617021 (-2960 1550);
PAINT SKYBLUE (-2960 1550);
FORCEPROP 1 LAST MATERIAL CHIP
J 0
(-2985 1650);
DISPLAY 0.617021 (-2985 1650);
PAINT SKYBLUE (-2985 1650);
FORCEPROP 1 LAST WATTAGE 1/16W
J 0
(-2985 1700);
DISPLAY 0.617021 (-2985 1700);
PAINT SKYBLUE (-2985 1700);
FORCEPROP 1 LAST PART_NUMBER G21497-005
J 0
(-2985 1600);
DISPLAY 0.617021 (-2985 1600);
PAINT BLUE (-2985 1600);
FORCEPROP 0 LAST GROUP PCIE_RISER
J 0
(-2982 1503);
DISPLAY 0.638298 (-2982 1503);
PAINT BROWN (-2982 1503);
DISPLAY BOTH (-2982 1503);
FORCEPROP 1 LAST PATH I72
J 0
(-2975 1900);
DISPLAY 0.978723 (-2975 1900);
PAINT WHITE (-2975 1900);
DISPLAY INVISIBLE (-2975 1900);
FORCEPROP 0 LAST CDS_LOCATION R774
J 0
(-2975 1900);
PAINT MONO (-2975 1900);
DISPLAY INVISIBLE (-2975 1900);
FORCEPROP 2 LAST CDS_LIB mstr_discrete
J 0
(-3025 1725);
PAINT MONO (-3025 1725);
DISPLAY INVISIBLE (-3025 1725);
FORCEPROP 2 LAST ROOM PCIE_STEERING
J 0
(-2975 1900);
PAINT MONO (-2975 1900);
DISPLAY INVISIBLE (-2975 1900);
FORCEPROP 0 LAST SEC 1
J 0
(-2975 1900);
PAINT MONO (-2975 1900);
DISPLAY INVISIBLE (-2975 1900);
FORCEPROP 2 LAST SEC_TYPE 0402
J 0
(-2975 1950);
DISPLAY 1.021277 (-2975 1950);
PAINT ORANGE (-2975 1950);
DISPLAY INVISIBLE (-2975 1950);
FORCEADD TAP..7
(-2625 1475);
FORCEPROP 3 LASTPIN (-2625 1525) SIG_NAME P3E_CPU0_PE1_PCH_CON_RXP<11>
J 0
(-2615 1535);
DISPLAY 0.659574 (-2615 1535);
PAINT MONO (-2615 1535);
DISPLAY INVISIBLE (-2615 1535);
FORCEPROP 1 LASTPIN (-2625 1525) BN 11
R 1
J 0
(-2632 1473);
DISPLAY 0.680851 (-2632 1473);
PAINT GREEN (-2632 1473);
FORCEPROP 1 LAST PATH I73
J 0
(-2627 1475);
DISPLAY 0.872340 (-2627 1475);
PAINT GREEN (-2627 1475);
DISPLAY INVISIBLE (-2627 1475);
FORCEPROP 2 LAST CDS_LIB mstr_standard
J 0
(-2625 1475);
PAINT MONO (-2625 1475);
DISPLAY INVISIBLE (-2625 1475);
FORCEPROP 1 LAST BODY_TYPE PLUMBING
J 0
(-2575 1475);
DISPLAY 2.276596 (-2575 1475);
PAINT GREEN (-2575 1475);
DISPLAY INVISIBLE (-2575 1475);
FORCEPROP 1 LAST HDL_TAP TRUE
J 0
(-2305 1345);
DISPLAY 2.276596 (-2305 1345);
PAINT GREEN (-2305 1345);
DISPLAY INVISIBLE (-2305 1345);
FORCEADD RES..2
(-2625 1725);
FORCEPROP 1 LAST MATERIAL CHIP
J 0
(-2585 1650);
DISPLAY 0.617021 (-2585 1650);
PAINT SKYBLUE (-2585 1650);
FORCEPROP 1 LASTPIN (-2625 1625) $PN 2
J 0
(-2620 1635);
DISPLAY 0.787234 (-2620 1635);
PAINT ORANGE (-2620 1635);
FORCEPROP 1 LAST $LOCATION R779
J 0
(-2580 1850);
DISPLAY 0.617021 (-2580 1850);
PAINT AQUA (-2580 1850);
FORCEPROP 1 LASTPIN (-2625 1825) $PN 1
J 0
(-2620 1787);
DISPLAY 0.787234 (-2620 1787);
PAINT ORANGE (-2620 1787);
FORCEPROP 1 LAST TOLERANCE 5%
J 0
(-2580 1750);
DISPLAY 0.617021 (-2580 1750);
PAINT SKYBLUE (-2580 1750);
FORCEPROP 1 LAST PART_NUMBER G21497-005
J 0
(-2585 1600);
DISPLAY 0.617021 (-2585 1600);
PAINT BLUE (-2585 1600);
FORCEPROP 1 LAST WATTAGE 1/16W
J 0
(-2585 1700);
DISPLAY 0.617021 (-2585 1700);
PAINT SKYBLUE (-2585 1700);
FORCEPROP 1 LAST PACK_TYPE 0402
J 0
(-2560 1550);
DISPLAY 0.617021 (-2560 1550);
PAINT SKYBLUE (-2560 1550);
FORCEPROP 0 LAST GROUP PCIE_RISER
J 0
(-2557 1503);
DISPLAY 0.638298 (-2557 1503);
PAINT BROWN (-2557 1503);
DISPLAY BOTH (-2557 1503);
FORCEPROP 1 LAST VALUE 0.0
J 0
(-2580 1800);
DISPLAY 0.617021 (-2580 1800);
PAINT SKYBLUE (-2580 1800);
FORCEPROP 1 LAST PATH I74
J 0
(-2575 1900);
DISPLAY 0.978723 (-2575 1900);
PAINT WHITE (-2575 1900);
DISPLAY INVISIBLE (-2575 1900);
FORCEPROP 0 LAST CDS_LOCATION R779
J 0
(-2575 1900);
PAINT MONO (-2575 1900);
DISPLAY INVISIBLE (-2575 1900);
FORCEPROP 2 LAST CDS_LIB mstr_discrete
J 0
(-2625 1725);
PAINT MONO (-2625 1725);
DISPLAY INVISIBLE (-2625 1725);
FORCEPROP 2 LAST ROOM PCIE_STEERING
J 0
(-2575 1900);
PAINT MONO (-2575 1900);
DISPLAY INVISIBLE (-2575 1900);
FORCEPROP 0 LAST SEC 1
J 0
(-2575 1900);
PAINT MONO (-2575 1900);
DISPLAY INVISIBLE (-2575 1900);
FORCEPROP 2 LAST SEC_TYPE 0402
J 0
(-2575 1950);
DISPLAY 1.021277 (-2575 1950);
PAINT ORANGE (-2575 1950);
DISPLAY INVISIBLE (-2575 1950);
FORCEADD TAP..7
(-2425 1475);
FORCEPROP 3 LASTPIN (-2425 1525) SIG_NAME P3E_CPU0_PE1_PCH_CON_RXP<10>
J 0
(-2415 1535);
DISPLAY 0.659574 (-2415 1535);
PAINT MONO (-2415 1535);
DISPLAY INVISIBLE (-2415 1535);
FORCEPROP 1 LASTPIN (-2425 1525) BN 10
R 1
J 0
(-2432 1473);
DISPLAY 0.680851 (-2432 1473);
PAINT GREEN (-2432 1473);
FORCEPROP 1 LAST PATH I75
J 0
(-2427 1475);
DISPLAY 0.872340 (-2427 1475);
PAINT GREEN (-2427 1475);
DISPLAY INVISIBLE (-2427 1475);
FORCEPROP 2 LAST CDS_LIB mstr_standard
J 0
(-2425 1475);
PAINT MONO (-2425 1475);
DISPLAY INVISIBLE (-2425 1475);
FORCEPROP 1 LAST BODY_TYPE PLUMBING
J 0
(-2375 1475);
DISPLAY 2.276596 (-2375 1475);
PAINT GREEN (-2375 1475);
DISPLAY INVISIBLE (-2375 1475);
FORCEPROP 1 LAST HDL_TAP TRUE
J 0
(-2105 1345);
DISPLAY 2.276596 (-2105 1345);
PAINT GREEN (-2105 1345);
DISPLAY INVISIBLE (-2105 1345);
FORCEADD TAP..7
(-2225 1475);
FORCEPROP 3 LASTPIN (-2225 1525) SIG_NAME P3E_CPU0_PE1_PCH_CON_RXP<9>
J 0
(-2215 1535);
DISPLAY 0.659574 (-2215 1535);
PAINT MONO (-2215 1535);
DISPLAY INVISIBLE (-2215 1535);
FORCEPROP 1 LASTPIN (-2225 1525) BN 9
R 1
J 0
(-2232 1473);
DISPLAY 0.680851 (-2232 1473);
PAINT GREEN (-2232 1473);
FORCEPROP 1 LAST PATH I76
J 0
(-2227 1475);
DISPLAY 0.872340 (-2227 1475);
PAINT GREEN (-2227 1475);
DISPLAY INVISIBLE (-2227 1475);
FORCEPROP 2 LAST CDS_LIB mstr_standard
J 0
(-2225 1475);
PAINT MONO (-2225 1475);
DISPLAY INVISIBLE (-2225 1475);
FORCEPROP 1 LAST BODY_TYPE PLUMBING
J 0
(-2175 1475);
DISPLAY 2.276596 (-2175 1475);
PAINT GREEN (-2175 1475);
DISPLAY INVISIBLE (-2175 1475);
FORCEPROP 1 LAST HDL_TAP TRUE
J 0
(-1905 1345);
DISPLAY 2.276596 (-1905 1345);
PAINT GREEN (-1905 1345);
DISPLAY INVISIBLE (-1905 1345);
FORCEADD RES..2
(-2225 1725);
FORCEPROP 1 LAST TOLERANCE 5%
J 0
(-2180 1750);
DISPLAY 0.617021 (-2180 1750);
PAINT SKYBLUE (-2180 1750);
FORCEPROP 1 LAST VALUE 0.0
J 0
(-2180 1800);
DISPLAY 0.617021 (-2180 1800);
PAINT SKYBLUE (-2180 1800);
FORCEPROP 1 LAST $LOCATION R783
J 0
(-2180 1850);
DISPLAY 0.617021 (-2180 1850);
PAINT AQUA (-2180 1850);
FORCEPROP 1 LASTPIN (-2225 1825) $PN 1
J 0
(-2220 1787);
DISPLAY 0.787234 (-2220 1787);
PAINT ORANGE (-2220 1787);
FORCEPROP 1 LAST PACK_TYPE 0402
J 0
(-2135 1550);
DISPLAY 0.617021 (-2135 1550);
PAINT SKYBLUE (-2135 1550);
FORCEPROP 1 LASTPIN (-2225 1625) $PN 2
J 0
(-2220 1635);
DISPLAY 0.787234 (-2220 1635);
PAINT ORANGE (-2220 1635);
FORCEPROP 1 LAST WATTAGE 1/16W
J 0
(-2185 1700);
DISPLAY 0.617021 (-2185 1700);
PAINT SKYBLUE (-2185 1700);
FORCEPROP 1 LAST PART_NUMBER G21497-005
J 0
(-2185 1600);
DISPLAY 0.617021 (-2185 1600);
PAINT BLUE (-2185 1600);
FORCEPROP 1 LAST MATERIAL CHIP
J 0
(-2185 1650);
DISPLAY 0.617021 (-2185 1650);
PAINT SKYBLUE (-2185 1650);
FORCEPROP 0 LAST GROUP PCIE_RISER
J 0
(-2157 1503);
DISPLAY 0.638298 (-2157 1503);
PAINT BROWN (-2157 1503);
DISPLAY BOTH (-2157 1503);
FORCEPROP 1 LAST PATH I77
J 0
(-2175 1900);
DISPLAY 0.978723 (-2175 1900);
PAINT WHITE (-2175 1900);
DISPLAY INVISIBLE (-2175 1900);
FORCEPROP 0 LAST CDS_LOCATION R783
J 0
(-2175 1900);
PAINT MONO (-2175 1900);
DISPLAY INVISIBLE (-2175 1900);
FORCEPROP 2 LAST CDS_LIB mstr_discrete
J 0
(-2225 1725);
PAINT MONO (-2225 1725);
DISPLAY INVISIBLE (-2225 1725);
FORCEPROP 2 LAST ROOM PCIE_STEERING
J 0
(-2175 1900);
PAINT MONO (-2175 1900);
DISPLAY INVISIBLE (-2175 1900);
FORCEPROP 0 LAST SEC 1
J 0
(-2175 1900);
PAINT MONO (-2175 1900);
DISPLAY INVISIBLE (-2175 1900);
FORCEPROP 2 LAST SEC_TYPE 0402
J 0
(-2175 1950);
DISPLAY 1.021277 (-2175 1950);
PAINT ORANGE (-2175 1950);
DISPLAY INVISIBLE (-2175 1950);
FORCEADD TAP..7
(-2025 1475);
FORCEPROP 3 LASTPIN (-2025 1525) SIG_NAME P3E_CPU0_PE1_PCH_CON_RXP<8>
J 0
(-2015 1535);
DISPLAY 0.659574 (-2015 1535);
PAINT MONO (-2015 1535);
DISPLAY INVISIBLE (-2015 1535);
FORCEPROP 1 LASTPIN (-2025 1525) BN 8
R 1
J 0
(-2032 1473);
DISPLAY 0.680851 (-2032 1473);
PAINT GREEN (-2032 1473);
FORCEPROP 1 LAST PATH I78
J 0
(-2027 1475);
DISPLAY 0.872340 (-2027 1475);
PAINT GREEN (-2027 1475);
DISPLAY INVISIBLE (-2027 1475);
FORCEPROP 2 LAST CDS_LIB mstr_standard
J 0
(-2025 1475);
PAINT MONO (-2025 1475);
DISPLAY INVISIBLE (-2025 1475);
FORCEPROP 1 LAST BODY_TYPE PLUMBING
J 0
(-1975 1475);
DISPLAY 2.276596 (-1975 1475);
PAINT GREEN (-1975 1475);
DISPLAY INVISIBLE (-1975 1475);
FORCEPROP 1 LAST HDL_TAP TRUE
J 0
(-1705 1345);
DISPLAY 2.276596 (-1705 1345);
PAINT GREEN (-1705 1345);
DISPLAY INVISIBLE (-1705 1345);
FORCEADD OFFPAGE..2
(-1725 1425);
FORCEPROP 2 LAST $XR1 109 
J 0
(-1416 1425);
DISPLAY 0.638298 (-1416 1425);
PAINT MONO (-1416 1425);
FORCEPROP 2 LAST $XR0 108 
J 0
(-1536 1425);
DISPLAY 0.638298 (-1536 1425);
PAINT MONO (-1536 1425);
FORCEPROP 2 LAST PATH I79
J 0
(-1525 1475);
DISPLAY 1.021277 (-1525 1475);
PAINT ORANGE (-1525 1475);
DISPLAY INVISIBLE (-1525 1475);
FORCEPROP 2 LAST CDS_LIB mstr_standard
J 0
(-1725 1425);
PAINT MONO (-1725 1425);
DISPLAY INVISIBLE (-1725 1425);
FORCEPROP 1 LAST OFFPAGE TRUE
J 0
(-1400 1300);
DISPLAY 0.872340 (-1400 1300);
PAINT GREEN (-1400 1300);
DISPLAY INVISIBLE (-1400 1300);
FORCEPROP 1 LAST COMMENT_BODY TRUE
J 0
(-1770 1330);
DISPLAY 0.872340 (-1770 1330);
PAINT GREEN (-1770 1330);
DISPLAY INVISIBLE (-1770 1330);
FORCEADD CAP..1
R 2
(-5125 1725);
FORCEPROP 1 LAST MATERIAL X7R
J 2
(-5175 1625);
DISPLAY 0.617021 (-5175 1625);
PAINT SKYBLUE (-5175 1625);
FORCEPROP 1 LAST TOLERANCE 10%
J 2
(-5175 1675);
DISPLAY 0.617021 (-5175 1675);
PAINT SKYBLUE (-5175 1675);
FORCEPROP 1 LAST VOLTAGE 16V
J 2
(-5175 1725);
DISPLAY 0.617021 (-5175 1725);
PAINT SKYBLUE (-5175 1725);
FORCEPROP 1 LAST VALUE 0.22UF
J 2
(-5175 1775);
DISPLAY 0.617021 (-5175 1775);
PAINT SKYBLUE (-5175 1775);
FORCEPROP 1 LAST $LOCATION C833
J 2
(-5175 1825);
DISPLAY 0.617021 (-5175 1825);
PAINT AQUA (-5175 1825);
FORCEPROP 1 LAST PACK_TYPE 0402
J 2
(-5175 1525);
DISPLAY 0.617021 (-5175 1525);
PAINT SKYBLUE (-5175 1525);
FORCEPROP 1 LASTPIN (-5125 1825) $PN 1
J 2
(-5135 1805);
DISPLAY 0.787234 (-5135 1805);
PAINT ORANGE (-5135 1805);
FORCEPROP 1 LASTPIN (-5125 1625) $PN 2
J 2
(-5135 1605);
DISPLAY 0.787234 (-5135 1605);
PAINT ORANGE (-5135 1605);
FORCEPROP 0 LAST GROUP PCIE_RISER
J 0
(-5307 1503);
DISPLAY 0.638298 (-5307 1503);
PAINT BROWN (-5307 1503);
DISPLAY BOTH (-5307 1503);
FORCEPROP 1 LAST PART_NUMBER A36096-155
J 2
(-5175 1575);
DISPLAY 0.617021 (-5175 1575);
PAINT BLUE (-5175 1575);
FORCEPROP 1 LAST PATH I8
J 2
(-5175 1875);
DISPLAY 0.978723 (-5175 1875);
PAINT WHITE (-5175 1875);
DISPLAY INVISIBLE (-5175 1875);
FORCEPROP 2 LAST CDS_LOCATION C833
J 2
(-5175 1825);
DISPLAY 0.617021 (-5175 1825);
PAINT AQUA (-5175 1825);
DISPLAY INVISIBLE (-5175 1825);
FORCEPROP 2 LAST CDS_LIB mstr_discrete
J 0
(-5125 1725);
PAINT MONO (-5125 1725);
DISPLAY INVISIBLE (-5125 1725);
FORCEPROP 2 LAST ROOM OCP_STEERING
J 2
(-5125 1725);
PAINT MONO (-5125 1725);
DISPLAY INVISIBLE (-5125 1725);
FORCEPROP 0 LAST SEC 1
J 0
(-5175 1875);
PAINT MONO (-5175 1875);
DISPLAY INVISIBLE (-5175 1875);
FORCEPROP 2 LAST SEC_TYPE 0402
J 0
(-5175 1925);
DISPLAY 1.021277 (-5175 1925);
PAINT ORANGE (-5175 1925);
DISPLAY INVISIBLE (-5175 1925);
FORCEADD RES..2
(-2825 2075);
FORCEPROP 0 LAST GROUP PCIE_RISER
J 0
(-2782 2253);
DISPLAY 0.638298 (-2782 2253);
PAINT BROWN (-2782 2253);
DISPLAY BOTH (-2782 2253);
FORCEPROP 1 LAST WATTAGE 1/16W
J 0
(-2785 2050);
DISPLAY 0.617021 (-2785 2050);
PAINT SKYBLUE (-2785 2050);
FORCEPROP 1 LAST TOLERANCE 5%
J 0
(-2780 2100);
DISPLAY 0.617021 (-2780 2100);
PAINT SKYBLUE (-2780 2100);
FORCEPROP 1 LAST MATERIAL CHIP
J 0
(-2785 2000);
DISPLAY 0.617021 (-2785 2000);
PAINT SKYBLUE (-2785 2000);
FORCEPROP 1 LAST $LOCATION R777
J 0
(-2780 2200);
DISPLAY 0.617021 (-2780 2200);
PAINT AQUA (-2780 2200);
FORCEPROP 1 LASTPIN (-2825 2175) $PN 1
J 0
(-2820 2137);
DISPLAY 0.787234 (-2820 2137);
PAINT ORANGE (-2820 2137);
FORCEPROP 1 LASTPIN (-2825 1975) $PN 2
J 0
(-2820 1985);
DISPLAY 0.787234 (-2820 1985);
PAINT ORANGE (-2820 1985);
FORCEPROP 1 LAST PART_NUMBER G21497-005
J 0
(-2785 1950);
DISPLAY 0.617021 (-2785 1950);
PAINT BLUE (-2785 1950);
FORCEPROP 1 LAST VALUE 0.0
J 0
(-2780 2150);
DISPLAY 0.617021 (-2780 2150);
PAINT SKYBLUE (-2780 2150);
FORCEPROP 1 LAST PACK_TYPE 0402
J 0
(-2735 1900);
DISPLAY 0.617021 (-2735 1900);
PAINT SKYBLUE (-2735 1900);
FORCEPROP 1 LAST PATH I80
J 0
(-2775 2250);
DISPLAY 0.978723 (-2775 2250);
PAINT WHITE (-2775 2250);
DISPLAY INVISIBLE (-2775 2250);
FORCEPROP 0 LAST CDS_LOCATION R777
J 0
(-2775 2250);
PAINT MONO (-2775 2250);
DISPLAY INVISIBLE (-2775 2250);
FORCEPROP 2 LAST CDS_LIB mstr_discrete
J 0
(-2825 2075);
PAINT MONO (-2825 2075);
DISPLAY INVISIBLE (-2825 2075);
FORCEPROP 2 LAST ROOM PCIE_STEERING
J 0
(-2775 2250);
PAINT MONO (-2775 2250);
DISPLAY INVISIBLE (-2775 2250);
FORCEPROP 0 LAST SEC 1
J 0
(-2775 2250);
PAINT MONO (-2775 2250);
DISPLAY INVISIBLE (-2775 2250);
FORCEPROP 2 LAST SEC_TYPE 0402
J 0
(-2775 2300);
DISPLAY 1.021277 (-2775 2300);
PAINT ORANGE (-2775 2300);
DISPLAY INVISIBLE (-2775 2300);
FORCEADD TAP..3
(-3025 2275);
FORCEPROP 3 LASTPIN (-3025 2225) SIG_NAME P3E_CPU0_PE1_PCH_RXP<13>
J 0
(-3015 2235);
DISPLAY 0.659574 (-3015 2235);
PAINT MONO (-3015 2235);
DISPLAY INVISIBLE (-3015 2235);
FORCEPROP 1 LASTPIN (-3025 2225) BN 13
R 1
J 0
(-3032 2213);
DISPLAY 0.680851 (-3032 2213);
PAINT GREEN (-3032 2213);
FORCEPROP 1 LAST PATH I81
J 0
(-3027 2275);
DISPLAY 0.872340 (-3027 2275);
PAINT GREEN (-3027 2275);
DISPLAY INVISIBLE (-3027 2275);
FORCEPROP 2 LAST CDS_LIB mstr_standard
J 0
(-3025 2275);
PAINT MONO (-3025 2275);
DISPLAY INVISIBLE (-3025 2275);
FORCEPROP 1 LAST BODY_TYPE PLUMBING
J 0
(-2975 2225);
DISPLAY 2.276596 (-2975 2225);
PAINT GREEN (-2975 2225);
DISPLAY INVISIBLE (-2975 2225);
FORCEPROP 1 LAST HDL_TAP TRUE
J 0
(-2705 2145);
DISPLAY 2.276596 (-2705 2145);
PAINT GREEN (-2705 2145);
DISPLAY INVISIBLE (-2705 2145);
FORCEADD TAP..3
(-2825 2275);
FORCEPROP 3 LASTPIN (-2825 2225) SIG_NAME P3E_CPU0_PE1_PCH_RXP<12>
J 0
(-2815 2235);
DISPLAY 0.659574 (-2815 2235);
PAINT MONO (-2815 2235);
DISPLAY INVISIBLE (-2815 2235);
FORCEPROP 1 LASTPIN (-2825 2225) BN 12
R 1
J 0
(-2832 2213);
DISPLAY 0.680851 (-2832 2213);
PAINT GREEN (-2832 2213);
FORCEPROP 1 LAST PATH I82
J 0
(-2827 2275);
DISPLAY 0.872340 (-2827 2275);
PAINT GREEN (-2827 2275);
DISPLAY INVISIBLE (-2827 2275);
FORCEPROP 2 LAST CDS_LIB mstr_standard
J 0
(-2825 2275);
PAINT MONO (-2825 2275);
DISPLAY INVISIBLE (-2825 2275);
FORCEPROP 1 LAST BODY_TYPE PLUMBING
J 0
(-2775 2225);
DISPLAY 2.276596 (-2775 2225);
PAINT GREEN (-2775 2225);
DISPLAY INVISIBLE (-2775 2225);
FORCEPROP 1 LAST HDL_TAP TRUE
J 0
(-2505 2145);
DISPLAY 2.276596 (-2505 2145);
PAINT GREEN (-2505 2145);
DISPLAY INVISIBLE (-2505 2145);
FORCEADD TAP..3
(-2625 2275);
FORCEPROP 3 LASTPIN (-2625 2225) SIG_NAME P3E_CPU0_PE1_PCH_RXP<11>
J 0
(-2615 2235);
DISPLAY 0.659574 (-2615 2235);
PAINT MONO (-2615 2235);
DISPLAY INVISIBLE (-2615 2235);
FORCEPROP 1 LASTPIN (-2625 2225) BN 11
R 1
J 0
(-2632 2213);
DISPLAY 0.680851 (-2632 2213);
PAINT GREEN (-2632 2213);
FORCEPROP 1 LAST PATH I83
J 0
(-2627 2275);
DISPLAY 0.872340 (-2627 2275);
PAINT GREEN (-2627 2275);
DISPLAY INVISIBLE (-2627 2275);
FORCEPROP 2 LAST CDS_LIB mstr_standard
J 0
(-2625 2275);
PAINT MONO (-2625 2275);
DISPLAY INVISIBLE (-2625 2275);
FORCEPROP 1 LAST BODY_TYPE PLUMBING
J 0
(-2575 2225);
DISPLAY 2.276596 (-2575 2225);
PAINT GREEN (-2575 2225);
DISPLAY INVISIBLE (-2575 2225);
FORCEPROP 1 LAST HDL_TAP TRUE
J 0
(-2305 2145);
DISPLAY 2.276596 (-2305 2145);
PAINT GREEN (-2305 2145);
DISPLAY INVISIBLE (-2305 2145);
FORCEADD TAP..7
(-2900 2775);
FORCEPROP 3 LASTPIN (-2900 2825) SIG_NAME P3E_CPU0_PE1_PCH_CON_RXN<12>
J 0
(-2890 2835);
DISPLAY 0.659574 (-2890 2835);
PAINT MONO (-2890 2835);
DISPLAY INVISIBLE (-2890 2835);
FORCEPROP 1 LASTPIN (-2900 2825) BN 12
R 1
J 0
(-2907 2773);
DISPLAY 0.680851 (-2907 2773);
PAINT GREEN (-2907 2773);
FORCEPROP 1 LAST PATH I84
J 0
(-2902 2775);
DISPLAY 0.872340 (-2902 2775);
PAINT GREEN (-2902 2775);
DISPLAY INVISIBLE (-2902 2775);
FORCEPROP 2 LAST CDS_LIB mstr_standard
J 0
(-2900 2775);
PAINT MONO (-2900 2775);
DISPLAY INVISIBLE (-2900 2775);
FORCEPROP 1 LAST BODY_TYPE PLUMBING
J 0
(-2850 2775);
DISPLAY 2.276596 (-2850 2775);
PAINT GREEN (-2850 2775);
DISPLAY INVISIBLE (-2850 2775);
FORCEPROP 1 LAST HDL_TAP TRUE
J 0
(-2580 2645);
DISPLAY 2.276596 (-2580 2645);
PAINT GREEN (-2580 2645);
DISPLAY INVISIBLE (-2580 2645);
FORCEADD TAP..7
(-2700 2775);
FORCEPROP 3 LASTPIN (-2700 2825) SIG_NAME P3E_CPU0_PE1_PCH_CON_RXN<11>
J 0
(-2690 2835);
DISPLAY 0.659574 (-2690 2835);
PAINT MONO (-2690 2835);
DISPLAY INVISIBLE (-2690 2835);
FORCEPROP 1 LASTPIN (-2700 2825) BN 11
R 1
J 0
(-2707 2773);
DISPLAY 0.680851 (-2707 2773);
PAINT GREEN (-2707 2773);
FORCEPROP 1 LAST PATH I85
J 0
(-2702 2775);
DISPLAY 0.872340 (-2702 2775);
PAINT GREEN (-2702 2775);
DISPLAY INVISIBLE (-2702 2775);
FORCEPROP 2 LAST CDS_LIB mstr_standard
J 0
(-2700 2775);
PAINT MONO (-2700 2775);
DISPLAY INVISIBLE (-2700 2775);
FORCEPROP 1 LAST BODY_TYPE PLUMBING
J 0
(-2650 2775);
DISPLAY 2.276596 (-2650 2775);
PAINT GREEN (-2650 2775);
DISPLAY INVISIBLE (-2650 2775);
FORCEPROP 1 LAST HDL_TAP TRUE
J 0
(-2380 2645);
DISPLAY 2.276596 (-2380 2645);
PAINT GREEN (-2380 2645);
DISPLAY INVISIBLE (-2380 2645);
FORCEADD RES..2
(-2425 2075);
FORCEPROP 1 LAST TOLERANCE 5%
J 0
(-2380 2100);
DISPLAY 0.617021 (-2380 2100);
PAINT SKYBLUE (-2380 2100);
FORCEPROP 1 LAST MATERIAL CHIP
J 0
(-2385 2000);
DISPLAY 0.617021 (-2385 2000);
PAINT SKYBLUE (-2385 2000);
FORCEPROP 1 LAST WATTAGE 1/16W
J 0
(-2385 2050);
DISPLAY 0.617021 (-2385 2050);
PAINT SKYBLUE (-2385 2050);
FORCEPROP 1 LAST VALUE 0.0
J 0
(-2380 2150);
DISPLAY 0.617021 (-2380 2150);
PAINT SKYBLUE (-2380 2150);
FORCEPROP 1 LASTPIN (-2425 2175) $PN 1
J 0
(-2420 2137);
DISPLAY 0.787234 (-2420 2137);
PAINT ORANGE (-2420 2137);
FORCEPROP 1 LASTPIN (-2425 1975) $PN 2
J 0
(-2420 1985);
DISPLAY 0.787234 (-2420 1985);
PAINT ORANGE (-2420 1985);
FORCEPROP 1 LAST PACK_TYPE 0402
J 0
(-2335 1900);
DISPLAY 0.617021 (-2335 1900);
PAINT SKYBLUE (-2335 1900);
FORCEPROP 1 LAST PART_NUMBER G21497-005
J 0
(-2385 1950);
DISPLAY 0.617021 (-2385 1950);
PAINT BLUE (-2385 1950);
FORCEPROP 1 LAST $LOCATION R781
J 0
(-2380 2200);
DISPLAY 0.617021 (-2380 2200);
PAINT AQUA (-2380 2200);
FORCEPROP 0 LAST GROUP PCIE_RISER
J 0
(-2382 2253);
DISPLAY 0.638298 (-2382 2253);
PAINT BROWN (-2382 2253);
DISPLAY BOTH (-2382 2253);
FORCEPROP 1 LAST PATH I86
J 0
(-2375 2250);
DISPLAY 0.978723 (-2375 2250);
PAINT WHITE (-2375 2250);
DISPLAY INVISIBLE (-2375 2250);
FORCEPROP 0 LAST CDS_LOCATION R781
J 0
(-2375 2250);
PAINT MONO (-2375 2250);
DISPLAY INVISIBLE (-2375 2250);
FORCEPROP 2 LAST CDS_LIB mstr_discrete
J 0
(-2425 2075);
PAINT MONO (-2425 2075);
DISPLAY INVISIBLE (-2425 2075);
FORCEPROP 2 LAST ROOM PCIE_STEERING
J 0
(-2375 2250);
PAINT MONO (-2375 2250);
DISPLAY INVISIBLE (-2375 2250);
FORCEPROP 0 LAST SEC 1
J 0
(-2375 2250);
PAINT MONO (-2375 2250);
DISPLAY INVISIBLE (-2375 2250);
FORCEPROP 2 LAST SEC_TYPE 0402
J 0
(-2375 2300);
DISPLAY 1.021277 (-2375 2300);
PAINT ORANGE (-2375 2300);
DISPLAY INVISIBLE (-2375 2300);
FORCEADD TAP..3
(-2425 2275);
FORCEPROP 3 LASTPIN (-2425 2225) SIG_NAME P3E_CPU0_PE1_PCH_RXP<10>
J 0
(-2415 2235);
DISPLAY 0.659574 (-2415 2235);
PAINT MONO (-2415 2235);
DISPLAY INVISIBLE (-2415 2235);
FORCEPROP 1 LASTPIN (-2425 2225) BN 10
R 1
J 0
(-2432 2213);
DISPLAY 0.680851 (-2432 2213);
PAINT GREEN (-2432 2213);
FORCEPROP 1 LAST PATH I87
J 0
(-2427 2275);
DISPLAY 0.872340 (-2427 2275);
PAINT GREEN (-2427 2275);
DISPLAY INVISIBLE (-2427 2275);
FORCEPROP 2 LAST CDS_LIB mstr_standard
J 0
(-2425 2275);
PAINT MONO (-2425 2275);
DISPLAY INVISIBLE (-2425 2275);
FORCEPROP 1 LAST BODY_TYPE PLUMBING
J 0
(-2375 2225);
DISPLAY 2.276596 (-2375 2225);
PAINT GREEN (-2375 2225);
DISPLAY INVISIBLE (-2375 2225);
FORCEPROP 1 LAST HDL_TAP TRUE
J 0
(-2105 2145);
DISPLAY 2.276596 (-2105 2145);
PAINT GREEN (-2105 2145);
DISPLAY INVISIBLE (-2105 2145);
FORCEADD TAP..3
(-2225 2275);
FORCEPROP 3 LASTPIN (-2225 2225) SIG_NAME P3E_CPU0_PE1_PCH_RXP<9>
J 0
(-2215 2235);
DISPLAY 0.659574 (-2215 2235);
PAINT MONO (-2215 2235);
DISPLAY INVISIBLE (-2215 2235);
FORCEPROP 1 LASTPIN (-2225 2225) BN 9
R 1
J 0
(-2232 2213);
DISPLAY 0.680851 (-2232 2213);
PAINT GREEN (-2232 2213);
FORCEPROP 1 LAST PATH I88
J 0
(-2227 2275);
DISPLAY 0.872340 (-2227 2275);
PAINT GREEN (-2227 2275);
DISPLAY INVISIBLE (-2227 2275);
FORCEPROP 2 LAST CDS_LIB mstr_standard
J 0
(-2225 2275);
PAINT MONO (-2225 2275);
DISPLAY INVISIBLE (-2225 2275);
FORCEPROP 1 LAST BODY_TYPE PLUMBING
J 0
(-2175 2225);
DISPLAY 2.276596 (-2175 2225);
PAINT GREEN (-2175 2225);
DISPLAY INVISIBLE (-2175 2225);
FORCEPROP 1 LAST HDL_TAP TRUE
J 0
(-1905 2145);
DISPLAY 2.276596 (-1905 2145);
PAINT GREEN (-1905 2145);
DISPLAY INVISIBLE (-1905 2145);
FORCEADD TAP..3
(-2025 2275);
FORCEPROP 3 LASTPIN (-2025 2225) SIG_NAME P3E_CPU0_PE1_PCH_RXP<8>
J 0
(-2015 2235);
DISPLAY 0.659574 (-2015 2235);
PAINT MONO (-2015 2235);
DISPLAY INVISIBLE (-2015 2235);
FORCEPROP 1 LASTPIN (-2025 2225) BN 8
R 1
J 0
(-2032 2213);
DISPLAY 0.680851 (-2032 2213);
PAINT GREEN (-2032 2213);
FORCEPROP 1 LAST PATH I89
J 0
(-2027 2275);
DISPLAY 0.872340 (-2027 2275);
PAINT GREEN (-2027 2275);
DISPLAY INVISIBLE (-2027 2275);
FORCEPROP 2 LAST CDS_LIB mstr_standard
J 0
(-2025 2275);
PAINT MONO (-2025 2275);
DISPLAY INVISIBLE (-2025 2275);
FORCEPROP 1 LAST BODY_TYPE PLUMBING
J 0
(-1975 2225);
DISPLAY 2.276596 (-1975 2225);
PAINT GREEN (-1975 2225);
DISPLAY INVISIBLE (-1975 2225);
FORCEPROP 1 LAST HDL_TAP TRUE
J 0
(-1705 2145);
DISPLAY 2.276596 (-1705 2145);
PAINT GREEN (-1705 2145);
DISPLAY INVISIBLE (-1705 2145);
FORCEADD OFFPAGE..1
(-6100 2325);
FORCEPROP 2 LAST $XR1 105 
J 0
(-6471 2325);
DISPLAY 0.638298 (-6471 2325);
PAINT MONO (-6471 2325);
FORCEPROP 2 LAST $XR0 30 
J 0
(-6351 2325);
DISPLAY 0.638298 (-6351 2325);
PAINT MONO (-6351 2325);
FORCEPROP 2 LAST PATH I9
J 0
(-6300 2375);
DISPLAY 1.021277 (-6300 2375);
PAINT ORANGE (-6300 2375);
DISPLAY INVISIBLE (-6300 2375);
FORCEPROP 2 LAST CDS_LIB mstr_standard
J 0
(-6100 2325);
PAINT MONO (-6100 2325);
DISPLAY INVISIBLE (-6100 2325);
FORCEPROP 1 LAST OFFPAGE TRUE
J 0
(-5780 2195);
PAINT GREEN (-5780 2195);
DISPLAY INVISIBLE (-5780 2195);
FORCEPROP 1 LAST COMMENT_BODY TRUE
J 0
(-5980 2225);
DISPLAY 2.276596 (-5980 2225);
PAINT GREEN (-5980 2225);
DISPLAY INVISIBLE (-5980 2225);
FORCEADD TAP..7
(-2500 2775);
FORCEPROP 3 LASTPIN (-2500 2825) SIG_NAME P3E_CPU0_PE1_PCH_CON_RXN<10>
J 0
(-2490 2835);
DISPLAY 0.659574 (-2490 2835);
PAINT MONO (-2490 2835);
DISPLAY INVISIBLE (-2490 2835);
FORCEPROP 1 LASTPIN (-2500 2825) BN 10
R 1
J 0
(-2507 2773);
DISPLAY 0.680851 (-2507 2773);
PAINT GREEN (-2507 2773);
FORCEPROP 1 LAST HDL_TAP TRUE
J 0
(-2180 2645);
DISPLAY 2.276596 (-2180 2645);
PAINT GREEN (-2180 2645);
DISPLAY INVISIBLE (-2180 2645);
FORCEPROP 1 LAST BODY_TYPE PLUMBING
J 0
(-2450 2775);
DISPLAY 2.276596 (-2450 2775);
PAINT GREEN (-2450 2775);
DISPLAY INVISIBLE (-2450 2775);
FORCEPROP 2 LAST CDS_LIB mstr_standard
J 0
(-2500 2775);
PAINT MONO (-2500 2775);
DISPLAY INVISIBLE (-2500 2775);
FORCEPROP 1 LAST PATH I90
J 0
(-2502 2775);
DISPLAY 0.872340 (-2502 2775);
PAINT GREEN (-2502 2775);
DISPLAY INVISIBLE (-2502 2775);
FORCEADD TAP..7
(-2300 2775);
FORCEPROP 3 LASTPIN (-2300 2825) SIG_NAME P3E_CPU0_PE1_PCH_CON_RXN<9>
J 0
(-2290 2835);
DISPLAY 0.659574 (-2290 2835);
PAINT MONO (-2290 2835);
DISPLAY INVISIBLE (-2290 2835);
FORCEPROP 1 LASTPIN (-2300 2825) BN 9
R 1
J 0
(-2307 2773);
DISPLAY 0.680851 (-2307 2773);
PAINT GREEN (-2307 2773);
FORCEPROP 1 LAST PATH I91
J 0
(-2302 2775);
DISPLAY 0.872340 (-2302 2775);
PAINT GREEN (-2302 2775);
DISPLAY INVISIBLE (-2302 2775);
FORCEPROP 2 LAST CDS_LIB mstr_standard
J 0
(-2300 2775);
PAINT MONO (-2300 2775);
DISPLAY INVISIBLE (-2300 2775);
FORCEPROP 1 LAST BODY_TYPE PLUMBING
J 0
(-2250 2775);
DISPLAY 2.276596 (-2250 2775);
PAINT GREEN (-2250 2775);
DISPLAY INVISIBLE (-2250 2775);
FORCEPROP 1 LAST HDL_TAP TRUE
J 0
(-1980 2645);
DISPLAY 2.276596 (-1980 2645);
PAINT GREEN (-1980 2645);
DISPLAY INVISIBLE (-1980 2645);
FORCEADD TAP..7
(-2100 2775);
FORCEPROP 3 LASTPIN (-2100 2825) SIG_NAME P3E_CPU0_PE1_PCH_CON_RXN<8>
J 0
(-2090 2835);
DISPLAY 0.659574 (-2090 2835);
PAINT MONO (-2090 2835);
DISPLAY INVISIBLE (-2090 2835);
FORCEPROP 1 LASTPIN (-2100 2825) BN 8
R 1
J 0
(-2107 2773);
DISPLAY 0.680851 (-2107 2773);
PAINT GREEN (-2107 2773);
FORCEPROP 1 LAST PATH I92
J 0
(-2102 2775);
DISPLAY 0.872340 (-2102 2775);
PAINT GREEN (-2102 2775);
DISPLAY INVISIBLE (-2102 2775);
FORCEPROP 2 LAST CDS_LIB mstr_standard
J 0
(-2100 2775);
PAINT MONO (-2100 2775);
DISPLAY INVISIBLE (-2100 2775);
FORCEPROP 1 LAST BODY_TYPE PLUMBING
J 0
(-2050 2775);
DISPLAY 2.276596 (-2050 2775);
PAINT GREEN (-2050 2775);
DISPLAY INVISIBLE (-2050 2775);
FORCEPROP 1 LAST HDL_TAP TRUE
J 0
(-1780 2645);
DISPLAY 2.276596 (-1780 2645);
PAINT GREEN (-1780 2645);
DISPLAY INVISIBLE (-1780 2645);
FORCEADD RES..2
(-2900 3375);
FORCEPROP 1 LASTPIN (-2900 3275) $PN 2
J 0
(-2895 3285);
DISPLAY 0.787234 (-2895 3285);
PAINT ORANGE (-2895 3285);
FORCEPROP 1 LAST WATTAGE 1/16W
J 0
(-2860 3350);
DISPLAY 0.617021 (-2860 3350);
PAINT SKYBLUE (-2860 3350);
FORCEPROP 1 LAST TOLERANCE 5%
J 0
(-2855 3400);
DISPLAY 0.617021 (-2855 3400);
PAINT SKYBLUE (-2855 3400);
FORCEPROP 1 LAST PACK_TYPE 0402
J 0
(-2835 3200);
DISPLAY 0.617021 (-2835 3200);
PAINT SKYBLUE (-2835 3200);
FORCEPROP 1 LAST PART_NUMBER G21497-005
J 0
(-2860 3250);
DISPLAY 0.617021 (-2860 3250);
PAINT BLUE (-2860 3250);
FORCEPROP 1 LAST MATERIAL CHIP
J 0
(-2860 3300);
DISPLAY 0.617021 (-2860 3300);
PAINT SKYBLUE (-2860 3300);
FORCEPROP 1 LASTPIN (-2900 3475) $PN 1
J 0
(-2895 3437);
DISPLAY 0.787234 (-2895 3437);
PAINT ORANGE (-2895 3437);
FORCEPROP 1 LAST VALUE 0.0
J 0
(-2855 3450);
DISPLAY 0.617021 (-2855 3450);
PAINT SKYBLUE (-2855 3450);
FORCEPROP 1 LAST $LOCATION R775
J 0
(-2855 3500);
DISPLAY 0.617021 (-2855 3500);
PAINT AQUA (-2855 3500);
FORCEPROP 0 LAST GROUP PCIE_RISER
J 0
(-2882 3578);
DISPLAY 0.638298 (-2882 3578);
PAINT BROWN (-2882 3578);
DISPLAY BOTH (-2882 3578);
FORCEPROP 1 LAST PATH I93
J 0
(-2850 3550);
DISPLAY 0.978723 (-2850 3550);
PAINT WHITE (-2850 3550);
DISPLAY INVISIBLE (-2850 3550);
FORCEPROP 0 LAST CDS_LOCATION R775
J 0
(-2850 3550);
PAINT MONO (-2850 3550);
DISPLAY INVISIBLE (-2850 3550);
FORCEPROP 2 LAST CDS_LIB mstr_discrete
J 0
(-2900 3375);
PAINT MONO (-2900 3375);
DISPLAY INVISIBLE (-2900 3375);
FORCEPROP 2 LAST ROOM PCIE_STEERING
J 0
(-2850 3550);
PAINT MONO (-2850 3550);
DISPLAY INVISIBLE (-2850 3550);
FORCEPROP 2 LAST SEC_TYPE 0402
J 0
(-2850 3600);
DISPLAY 1.021277 (-2850 3600);
PAINT ORANGE (-2850 3600);
DISPLAY INVISIBLE (-2850 3600);
FORCEPROP 0 LAST SEC 1
J 0
(-2850 3550);
PAINT MONO (-2850 3550);
DISPLAY INVISIBLE (-2850 3550);
FORCEADD RES..2
(-2700 3025);
FORCEPROP 0 LAST GROUP PCIE_RISER
J 0
(-2682 2828);
DISPLAY 0.638298 (-2682 2828);
PAINT BROWN (-2682 2828);
DISPLAY BOTH (-2682 2828);
FORCEPROP 1 LAST WATTAGE 1/16W
J 0
(-2660 3000);
DISPLAY 0.617021 (-2660 3000);
PAINT SKYBLUE (-2660 3000);
FORCEPROP 1 LAST PART_NUMBER G21497-005
J 0
(-2660 2900);
DISPLAY 0.617021 (-2660 2900);
PAINT BLUE (-2660 2900);
FORCEPROP 1 LASTPIN (-2700 2925) $PN 2
J 0
(-2695 2935);
DISPLAY 0.787234 (-2695 2935);
PAINT ORANGE (-2695 2935);
FORCEPROP 1 LASTPIN (-2700 3125) $PN 1
J 0
(-2695 3087);
DISPLAY 0.787234 (-2695 3087);
PAINT ORANGE (-2695 3087);
FORCEPROP 1 LAST MATERIAL CHIP
J 0
(-2660 2950);
DISPLAY 0.617021 (-2660 2950);
PAINT SKYBLUE (-2660 2950);
FORCEPROP 1 LAST TOLERANCE 5%
J 0
(-2655 3050);
DISPLAY 0.617021 (-2655 3050);
PAINT SKYBLUE (-2655 3050);
FORCEPROP 1 LAST VALUE 0.0
J 0
(-2655 3100);
DISPLAY 0.617021 (-2655 3100);
PAINT SKYBLUE (-2655 3100);
FORCEPROP 1 LAST $LOCATION R778
J 0
(-2655 3150);
DISPLAY 0.617021 (-2655 3150);
PAINT AQUA (-2655 3150);
FORCEPROP 1 LAST PACK_TYPE 0402
J 0
(-2635 2850);
DISPLAY 0.617021 (-2635 2850);
PAINT SKYBLUE (-2635 2850);
FORCEPROP 2 LAST SEC_TYPE 0402
J 0
(-2650 3250);
DISPLAY 1.021277 (-2650 3250);
PAINT ORANGE (-2650 3250);
DISPLAY INVISIBLE (-2650 3250);
FORCEPROP 0 LAST SEC 1
J 0
(-2650 3200);
PAINT MONO (-2650 3200);
DISPLAY INVISIBLE (-2650 3200);
FORCEPROP 1 LAST PATH I94
J 0
(-2650 3200);
DISPLAY 0.978723 (-2650 3200);
PAINT WHITE (-2650 3200);
DISPLAY INVISIBLE (-2650 3200);
FORCEPROP 0 LAST CDS_LOCATION R778
J 0
(-2650 3200);
PAINT MONO (-2650 3200);
DISPLAY INVISIBLE (-2650 3200);
FORCEPROP 2 LAST CDS_LIB mstr_discrete
J 0
(-2700 3025);
PAINT MONO (-2700 3025);
DISPLAY INVISIBLE (-2700 3025);
FORCEPROP 2 LAST ROOM PCIE_STEERING
J 0
(-2650 3200);
PAINT MONO (-2650 3200);
DISPLAY INVISIBLE (-2650 3200);
FORCEADD TAP..3
(-2900 3575);
FORCEPROP 3 LASTPIN (-2900 3525) SIG_NAME P3E_CPU0_PE1_PCH_RXN<12>
J 0
(-2890 3535);
DISPLAY 0.659574 (-2890 3535);
PAINT MONO (-2890 3535);
DISPLAY INVISIBLE (-2890 3535);
FORCEPROP 1 LASTPIN (-2900 3525) BN 12
R 1
J 0
(-2907 3513);
DISPLAY 0.680851 (-2907 3513);
PAINT GREEN (-2907 3513);
FORCEPROP 1 LAST PATH I95
J 0
(-2902 3575);
DISPLAY 0.872340 (-2902 3575);
PAINT GREEN (-2902 3575);
DISPLAY INVISIBLE (-2902 3575);
FORCEPROP 2 LAST CDS_LIB mstr_standard
J 0
(-2900 3575);
PAINT MONO (-2900 3575);
DISPLAY INVISIBLE (-2900 3575);
FORCEPROP 1 LAST BODY_TYPE PLUMBING
J 0
(-2850 3525);
DISPLAY 2.276596 (-2850 3525);
PAINT GREEN (-2850 3525);
DISPLAY INVISIBLE (-2850 3525);
FORCEPROP 1 LAST HDL_TAP TRUE
J 0
(-2580 3445);
DISPLAY 2.276596 (-2580 3445);
PAINT GREEN (-2580 3445);
DISPLAY INVISIBLE (-2580 3445);
FORCEADD TAP..3
(-2700 3575);
FORCEPROP 3 LASTPIN (-2700 3525) SIG_NAME P3E_CPU0_PE1_PCH_RXN<11>
J 0
(-2690 3535);
DISPLAY 0.659574 (-2690 3535);
PAINT MONO (-2690 3535);
DISPLAY INVISIBLE (-2690 3535);
FORCEPROP 1 LASTPIN (-2700 3525) BN 11
R 1
J 0
(-2707 3513);
DISPLAY 0.680851 (-2707 3513);
PAINT GREEN (-2707 3513);
FORCEPROP 1 LAST PATH I96
J 0
(-2702 3575);
DISPLAY 0.872340 (-2702 3575);
PAINT GREEN (-2702 3575);
DISPLAY INVISIBLE (-2702 3575);
FORCEPROP 2 LAST CDS_LIB mstr_standard
J 0
(-2700 3575);
PAINT MONO (-2700 3575);
DISPLAY INVISIBLE (-2700 3575);
FORCEPROP 1 LAST BODY_TYPE PLUMBING
J 0
(-2650 3525);
DISPLAY 2.276596 (-2650 3525);
PAINT GREEN (-2650 3525);
DISPLAY INVISIBLE (-2650 3525);
FORCEPROP 1 LAST HDL_TAP TRUE
J 0
(-2380 3445);
DISPLAY 2.276596 (-2380 3445);
PAINT GREEN (-2380 3445);
DISPLAY INVISIBLE (-2380 3445);
FORCEADD RES..2
(-2500 3375);
FORCEPROP 1 LAST PART_NUMBER G21497-005
J 0
(-2460 3250);
DISPLAY 0.617021 (-2460 3250);
PAINT BLUE (-2460 3250);
FORCEPROP 1 LAST MATERIAL CHIP
J 0
(-2460 3300);
DISPLAY 0.617021 (-2460 3300);
PAINT SKYBLUE (-2460 3300);
FORCEPROP 1 LAST TOLERANCE 5%
J 0
(-2455 3400);
DISPLAY 0.617021 (-2455 3400);
PAINT SKYBLUE (-2455 3400);
FORCEPROP 1 LASTPIN (-2500 3475) $PN 1
J 0
(-2495 3437);
DISPLAY 0.787234 (-2495 3437);
PAINT ORANGE (-2495 3437);
FORCEPROP 1 LAST $LOCATION R780
J 0
(-2455 3500);
DISPLAY 0.617021 (-2455 3500);
PAINT AQUA (-2455 3500);
FORCEPROP 1 LASTPIN (-2500 3275) $PN 2
J 0
(-2495 3285);
DISPLAY 0.787234 (-2495 3285);
PAINT ORANGE (-2495 3285);
FORCEPROP 1 LAST PACK_TYPE 0402
J 0
(-2410 3200);
DISPLAY 0.617021 (-2410 3200);
PAINT SKYBLUE (-2410 3200);
FORCEPROP 1 LAST WATTAGE 1/16W
J 0
(-2460 3350);
DISPLAY 0.617021 (-2460 3350);
PAINT SKYBLUE (-2460 3350);
FORCEPROP 1 LAST VALUE 0.0
J 0
(-2455 3450);
DISPLAY 0.617021 (-2455 3450);
PAINT SKYBLUE (-2455 3450);
FORCEPROP 0 LAST GROUP PCIE_RISER
J 0
(-2482 3578);
DISPLAY 0.638298 (-2482 3578);
PAINT BROWN (-2482 3578);
DISPLAY BOTH (-2482 3578);
FORCEPROP 2 LAST SEC_TYPE 0402
J 0
(-2450 3600);
DISPLAY 1.021277 (-2450 3600);
PAINT ORANGE (-2450 3600);
DISPLAY INVISIBLE (-2450 3600);
FORCEPROP 0 LAST SEC 1
J 0
(-2450 3550);
PAINT MONO (-2450 3550);
DISPLAY INVISIBLE (-2450 3550);
FORCEPROP 2 LAST ROOM PCIE_STEERING
J 0
(-2450 3550);
PAINT MONO (-2450 3550);
DISPLAY INVISIBLE (-2450 3550);
FORCEPROP 2 LAST CDS_LIB mstr_discrete
J 0
(-2500 3375);
PAINT MONO (-2500 3375);
DISPLAY INVISIBLE (-2500 3375);
FORCEPROP 0 LAST CDS_LOCATION R780
J 0
(-2450 3550);
PAINT MONO (-2450 3550);
DISPLAY INVISIBLE (-2450 3550);
FORCEPROP 1 LAST PATH I97
J 0
(-2450 3550);
DISPLAY 0.978723 (-2450 3550);
PAINT WHITE (-2450 3550);
DISPLAY INVISIBLE (-2450 3550);
FORCEADD RES..2
(-2300 3025);
FORCEPROP 1 LAST VALUE 0.0
J 0
(-2255 3100);
DISPLAY 0.617021 (-2255 3100);
PAINT SKYBLUE (-2255 3100);
FORCEPROP 1 LASTPIN (-2300 3125) $PN 1
J 0
(-2295 3087);
DISPLAY 0.787234 (-2295 3087);
PAINT ORANGE (-2295 3087);
FORCEPROP 1 LAST PART_NUMBER G21497-005
J 0
(-2260 2900);
DISPLAY 0.617021 (-2260 2900);
PAINT BLUE (-2260 2900);
FORCEPROP 1 LASTPIN (-2300 2925) $PN 2
J 0
(-2295 2935);
DISPLAY 0.787234 (-2295 2935);
PAINT ORANGE (-2295 2935);
FORCEPROP 1 LAST TOLERANCE 5%
J 0
(-2255 3050);
DISPLAY 0.617021 (-2255 3050);
PAINT SKYBLUE (-2255 3050);
FORCEPROP 1 LAST WATTAGE 1/16W
J 0
(-2260 3000);
DISPLAY 0.617021 (-2260 3000);
PAINT SKYBLUE (-2260 3000);
FORCEPROP 1 LAST MATERIAL CHIP
J 0
(-2260 2950);
DISPLAY 0.617021 (-2260 2950);
PAINT SKYBLUE (-2260 2950);
FORCEPROP 1 LAST $LOCATION R782
J 0
(-2255 3150);
DISPLAY 0.617021 (-2255 3150);
PAINT AQUA (-2255 3150);
FORCEPROP 1 LAST PACK_TYPE 0402
J 0
(-2235 2850);
DISPLAY 0.617021 (-2235 2850);
PAINT SKYBLUE (-2235 2850);
FORCEPROP 0 LAST GROUP PCIE_RISER
J 0
(-2257 2828);
DISPLAY 0.638298 (-2257 2828);
PAINT BROWN (-2257 2828);
DISPLAY BOTH (-2257 2828);
FORCEPROP 2 LAST SEC_TYPE 0402
J 0
(-2250 3250);
DISPLAY 1.021277 (-2250 3250);
PAINT ORANGE (-2250 3250);
DISPLAY INVISIBLE (-2250 3250);
FORCEPROP 0 LAST SEC 1
J 0
(-2250 3200);
PAINT MONO (-2250 3200);
DISPLAY INVISIBLE (-2250 3200);
FORCEPROP 1 LAST PATH I98
J 0
(-2250 3200);
DISPLAY 0.978723 (-2250 3200);
PAINT WHITE (-2250 3200);
DISPLAY INVISIBLE (-2250 3200);
FORCEPROP 0 LAST CDS_LOCATION R782
J 0
(-2250 3200);
PAINT MONO (-2250 3200);
DISPLAY INVISIBLE (-2250 3200);
FORCEPROP 2 LAST CDS_LIB mstr_discrete
J 0
(-2300 3025);
PAINT MONO (-2300 3025);
DISPLAY INVISIBLE (-2300 3025);
FORCEPROP 2 LAST ROOM PCIE_STEERING
J 0
(-2250 3200);
PAINT MONO (-2250 3200);
DISPLAY INVISIBLE (-2250 3200);
FORCEADD RES..2
(-2100 3375);
FORCEPROP 1 LAST VALUE 0.0
J 0
(-2055 3450);
DISPLAY 0.617021 (-2055 3450);
PAINT SKYBLUE (-2055 3450);
FORCEPROP 1 LAST TOLERANCE 5%
J 0
(-2055 3400);
DISPLAY 0.617021 (-2055 3400);
PAINT SKYBLUE (-2055 3400);
FORCEPROP 1 LAST WATTAGE 1/16W
J 0
(-2060 3350);
DISPLAY 0.617021 (-2060 3350);
PAINT SKYBLUE (-2060 3350);
FORCEPROP 1 LASTPIN (-2100 3475) $PN 1
J 0
(-2095 3437);
DISPLAY 0.787234 (-2095 3437);
PAINT ORANGE (-2095 3437);
FORCEPROP 1 LAST MATERIAL CHIP
J 0
(-2060 3300);
DISPLAY 0.617021 (-2060 3300);
PAINT SKYBLUE (-2060 3300);
FORCEPROP 1 LASTPIN (-2100 3275) $PN 2
J 0
(-2095 3285);
DISPLAY 0.787234 (-2095 3285);
PAINT ORANGE (-2095 3285);
FORCEPROP 0 LAST GROUP PCIE_RISER
J 0
(-2082 3578);
DISPLAY 0.638298 (-2082 3578);
PAINT BROWN (-2082 3578);
DISPLAY BOTH (-2082 3578);
FORCEPROP 1 LAST $LOCATION R784
J 0
(-2055 3500);
DISPLAY 0.617021 (-2055 3500);
PAINT AQUA (-2055 3500);
FORCEPROP 1 LAST PART_NUMBER G21497-005
J 0
(-2060 3250);
DISPLAY 0.617021 (-2060 3250);
PAINT BLUE (-2060 3250);
FORCEPROP 1 LAST PACK_TYPE 0402
J 0
(-2035 3200);
DISPLAY 0.617021 (-2035 3200);
PAINT SKYBLUE (-2035 3200);
FORCEPROP 0 LAST SEC 1
J 0
(-2050 3550);
PAINT MONO (-2050 3550);
DISPLAY INVISIBLE (-2050 3550);
FORCEPROP 2 LAST SEC_TYPE 0402
J 0
(-2050 3600);
DISPLAY 1.021277 (-2050 3600);
PAINT ORANGE (-2050 3600);
DISPLAY INVISIBLE (-2050 3600);
FORCEPROP 2 LAST ROOM PCIE_STEERING
J 0
(-2050 3550);
PAINT MONO (-2050 3550);
DISPLAY INVISIBLE (-2050 3550);
FORCEPROP 2 LAST CDS_LIB mstr_discrete
J 0
(-2100 3375);
PAINT MONO (-2100 3375);
DISPLAY INVISIBLE (-2100 3375);
FORCEPROP 0 LAST CDS_LOCATION R784
J 0
(-2050 3550);
PAINT MONO (-2050 3550);
DISPLAY INVISIBLE (-2050 3550);
FORCEPROP 1 LAST PATH I99
J 0
(-2050 3550);
DISPLAY 0.978723 (-2050 3550);
PAINT WHITE (-2050 3550);
DISPLAY INVISIBLE (-2050 3550);
FORCEADD INTEL_CORP_BPAGE..1
(0 0);
FORCEPROP 1 LAST CDS_CON_LAST_MODIFIED Fri Jun 16 17:49:28 2017
J 0
(-1425 325);
PAINT ORANGE (-1425 325);
DISPLAY INVISIBLE (-1425 325);
FORCEPROP 1 LAST CUSTOM_TXT_CDS <CURRENT_DESIGN_SHEET> OF <TOTAL_DESIGN_SHEETS>
J 0
(-500 25);
PAINT ORANGE (-500 25);
FORCEPROP 1 LAST CUSTOM_TXT_CDS <CON_LAST_MODIFIED>
J 0
(-4000 100);
PAINT ORANGE (-4000 100);
FORCEPROP 2 LAST CUSTOM_TXT_CDS <XR_PAGE_TITLE>
J 0
(-7890 5250);
DISPLAY 0.638298 (-7890 5250);
PAINT PINK (-7890 5250);
DISPLAY INVISIBLE (-7890 5250);
FORCEPROP 1 LAST SCH_TITLE x8 PCIe Co-lay path
J 0
(-7950 50);
DISPLAY 2.468085 (-7950 50);
PAINT ORANGE (-7950 50);
FORCEPROP 2 LAST PAGE_BORDER TRUE
J 0
(-7890 5250);
DISPLAY 0.638298 (-7890 5250);
PAINT PINK (-7890 5250);
DISPLAY INVISIBLE (-7890 5250);
FORCEPROP 2 LAST CDS_LIB mstr_symbols
J 0
(0 0);
PAINT MONO (0 0);
DISPLAY INVISIBLE (0 0);
FORCEPROP 1 LAST COMMENT_BODY TRUE
J 0
(12 12);
DISPLAY 0.468085 (12 12);
PAINT GREEN (12 12);
DISPLAY INVISIBLE (12 12);
FORCEPROP 2 LAST CDS_XR_PAGE_TITLE CR-244 : @BASEBOARD_FAB2_LIB.BASEBOARD_FAB2(SCH_1):PAGE244
J 0
(-7890 5250);
DISPLAY 0.638298 (-7890 5250);
PAINT PINK (-7890 5250);
DISPLAY INVISIBLE (-7890 5250);
WIRE 17 -1 (-2250 2325)(-2050 2325);
WIRE 17 -1 (-3450 2325)(-3550 2325);
FORCEPROP 2 LAST SIG_NAME P3E_CPU0_PE1_PCH_RXP<15:8>
J 0
(-3510 2360);
DISPLAY 1.021277 (-3510 2360);
PAINT ORANGE (-3510 2360);
WIRE 17 -1 (-2250 2325)(-2450 2325);
WIRE 17 -1 (-2450 2325)(-2650 2325);
WIRE 17 -1 (-3250 2325)(-3450 2325);
WIRE 17 -1 (-3050 2325)(-3250 2325);
WIRE 17 -1 (-2650 2325)(-2850 2325);
WIRE 17 -1 (-2850 2325)(-3050 2325);
WIRE 17 -1 (-3275 2725)(-3475 2725);
WIRE 17 -1 (-3075 2725)(-3275 2725);
FORCEPROP 2 LAST SIG_NAME P3E_CPU0_PE1_PCH_CON_RXN<15:8>
J 0
(-3185 2660);
DISPLAY 1.021277 (-3185 2660);
PAINT ORANGE (-3185 2660);
WIRE 17 -1 (-1850 2725)(-2075 2725);
WIRE 17 -1 (-2075 2725)(-2275 2725);
WIRE 17 -1 (-2875 2725)(-3075 2725);
WIRE 17 -1 (-2675 2725)(-2875 2725);
WIRE 17 -1 (-2275 2725)(-2475 2725);
WIRE 17 -1 (-2475 2725)(-2675 2725);
WIRE 17 -1 (-5800 2725)(-6000 2725);
WIRE 17 -1 (-5600 2725)(-5800 2725);
FORCEPROP 2 LAST SIG_NAME P3E_CPU0_PE1_PCH_CON_TXN<15:8>
J 0
(-5710 2660);
DISPLAY 1.021277 (-5710 2660);
PAINT ORANGE (-5710 2660);
WIRE 17 -1 (-5400 2725)(-5600 2725);
WIRE 17 -1 (-4375 2725)(-4600 2725);
WIRE 17 -1 (-5200 2725)(-5400 2725);
WIRE 17 -1 (-5000 2725)(-5200 2725);
WIRE 17 -1 (-4600 2725)(-4800 2725);
WIRE 17 -1 (-4800 2725)(-5000 2725);
WIRE 17 -1 (-2325 3625)(-2125 3625);
WIRE 17 -1 (-2325 3625)(-2525 3625);
WIRE 17 -1 (-2525 3625)(-2725 3625);
WIRE 17 -1 (-2725 3625)(-2925 3625);
WIRE 17 -1 (-2925 3625)(-3125 3625);
WIRE 17 -1 (-3525 3625)(-3625 3625);
FORCEPROP 2 LAST SIG_NAME P3E_CPU0_PE1_PCH_RXN<15:8>
J 0
(-3610 3660);
DISPLAY 1.021277 (-3610 3660);
PAINT ORANGE (-3610 3660);
WIRE 17 -1 (-3125 3625)(-3325 3625);
WIRE 17 -1 (-3325 3625)(-3525 3625);
WIRE 17 -1 (-3200 1425)(-3400 1425);
WIRE 17 -1 (-3000 1425)(-3200 1425);
FORCEPROP 2 LAST SIG_NAME P3E_CPU0_PE1_PCH_CON_RXP<15:8>
J 0
(-3085 1335);
DISPLAY 1.021277 (-3085 1335);
PAINT ORANGE (-3085 1335);
WIRE 17 -1 (-2800 1425)(-3000 1425);
WIRE 17 -1 (-2600 1425)(-2800 1425);
WIRE 17 -1 (-2400 1425)(-2600 1425);
WIRE 17 -1 (-2200 1425)(-2400 1425);
WIRE 17 -1 (-2000 1425)(-2200 1425);
WIRE 17 -1 (-1775 1425)(-2000 1425);
WIRE 17 -1 (-5700 1425)(-5900 1425);
WIRE 17 -1 (-5500 1425)(-5700 1425);
FORCEPROP 2 LAST SIG_NAME P3E_CPU0_PE1_PCH_CON_TXP<15:8>
J 0
(-5635 1360);
DISPLAY 1.021277 (-5635 1360);
PAINT ORANGE (-5635 1360);
WIRE 17 -1 (-5300 1425)(-5500 1425);
WIRE 17 -1 (-5100 1425)(-5300 1425);
WIRE 17 -1 (-4900 1425)(-5100 1425);
WIRE 17 -1 (-4700 1425)(-4900 1425);
WIRE 17 -1 (-4275 1425)(-4500 1425);
WIRE 17 -1 (-4500 1425)(-4700 1425);
WIRE 17 -1 (-4750 2325)(-4550 2325);
WIRE 17 -1 (-4750 2325)(-4950 2325);
WIRE 17 -1 (-4950 2325)(-5150 2325);
WIRE 17 -1 (-5150 2325)(-5350 2325);
WIRE 17 -1 (-5950 2325)(-6050 2325);
FORCEPROP 2 LAST SIG_NAME P3E_CPU0_PE1_PCH_TXP<15:8>
J 0
(-6010 2360);
DISPLAY 1.021277 (-6010 2360);
PAINT ORANGE (-6010 2360);
WIRE 17 -1 (-5750 2325)(-5950 2325);
WIRE 17 -1 (-5350 2325)(-5550 2325);
WIRE 17 -1 (-5550 2325)(-5750 2325);
WIRE 17 -1 (-6050 3625)(-6150 3625);
FORCEPROP 2 LAST SIG_NAME P3E_CPU0_PE1_PCH_TXN<15:8>
J 0
(-6085 3660);
DISPLAY 1.021277 (-6085 3660);
PAINT ORANGE (-6085 3660);
WIRE 17 -1 (-5850 3625)(-6050 3625);
WIRE 17 -1 (-5650 3625)(-5850 3625);
WIRE 17 -1 (-4850 3625)(-4650 3625);
WIRE 17 -1 (-5450 3625)(-5650 3625);
WIRE 17 -1 (-5250 3625)(-5450 3625);
WIRE 17 -1 (-4850 3625)(-5050 3625);
WIRE 17 -1 (-5050 3625)(-5250 3625);
WIRE 16 -1 (-2900 2825)(-2900 3275);
WIRE 16 -1 (-5625 2825)(-5625 2925);
WIRE 16 -1 (-4625 2825)(-4625 3200);
WIRE 16 -1 (-4725 1825)(-4725 2225);
WIRE 16 -1 (-4925 1525)(-4925 1925);
WIRE 16 -1 (-3425 2225)(-3425 1825);
WIRE 16 -1 (-5925 2225)(-5925 1825);
WIRE 16 -1 (-5225 2825)(-5225 2925);
WIRE 16 -1 (-2225 1525)(-2225 1625);
WIRE 16 -1 (-3225 1975)(-3225 1525);
WIRE 16 -1 (-3500 2825)(-3500 2925);
WIRE 16 -1 (-2500 2825)(-2500 3275);
WIRE 16 -1 (-2300 2825)(-2300 2925);
WIRE 16 -1 (-2100 2825)(-2100 3275);
WIRE 16 -1 (-2300 3125)(-2300 3525);
WIRE 16 -1 (-3100 3525)(-3100 3125);
WIRE 16 -1 (-3300 3275)(-3300 2825);
WIRE 16 -1 (-2100 3475)(-2100 3525);
WIRE 16 -1 (-2700 3525)(-2700 3125);
WIRE 16 -1 (-2825 1525)(-2825 1975);
WIRE 16 -1 (-2625 2225)(-2625 1825);
WIRE 16 -1 (-2425 1525)(-2425 1975);
WIRE 16 -1 (-6025 3525)(-6025 3125);
WIRE 16 -1 (-5325 2225)(-5325 2125);
WIRE 16 -1 (-5025 3425)(-5025 3525);
WIRE 16 -1 (-4625 3400)(-4625 3525);
WIRE 16 -1 (-4825 3125)(-4825 3525);
WIRE 16 -1 (-4925 2125)(-4925 2225);
WIRE 16 -1 (-5425 3525)(-5425 3425);
WIRE 16 -1 (-5625 3525)(-5625 3125);
WIRE 16 -1 (-5825 3525)(-5825 3425);
WIRE 16 -1 (-6025 2825)(-6025 2925);
WIRE 16 -1 (-5725 1925)(-5725 1525);
WIRE 16 -1 (-5525 1525)(-5525 1625);
WIRE 16 -1 (-5925 1525)(-5925 1625);
WIRE 16 -1 (-5825 3225)(-5825 2825);
WIRE 16 -1 (-5425 2825)(-5425 3225);
WIRE 16 -1 (-5225 3525)(-5225 3125);
WIRE 16 -1 (-4825 2825)(-4825 2925);
WIRE 16 -1 (-3300 3525)(-3300 3475);
WIRE 16 -1 (-2500 3475)(-2500 3525);
WIRE 16 -1 (-2900 3525)(-2900 3475);
WIRE 16 -1 (-4525 2125)(-4525 2225);
WIRE 16 -1 (-5525 2225)(-5525 1825);
WIRE 16 -1 (-4525 1525)(-4525 1925);
WIRE 16 -1 (-5125 2225)(-5125 1825);
WIRE 16 -1 (-5725 2225)(-5725 2125);
WIRE 16 -1 (-5125 1525)(-5125 1625);
WIRE 16 -1 (-5325 1525)(-5325 1925);
WIRE 16 -1 (-4725 1525)(-4725 1625);
WIRE 16 -1 (-3025 1525)(-3025 1625);
WIRE 16 -1 (-3425 1525)(-3425 1625);
WIRE 16 -1 (-3225 2225)(-3225 2175);
WIRE 16 -1 (-2825 2225)(-2825 2175);
WIRE 16 -1 (-2625 1525)(-2625 1625);
WIRE 16 -1 (-2425 2175)(-2425 2225);
WIRE 16 -1 (-2225 1825)(-2225 2225);
WIRE 16 -1 (-2025 1525)(-2025 1975);
WIRE 16 -1 (-2025 2175)(-2025 2225);
WIRE 3 2175 (-7475 4400)(-800 4400);
WIRE 3 2175 (-800 4400)(-800 650);
WIRE 3 2175 (-7475 4400)(-7475 650);
WIRE 3 2175 (-7475 650)(-800 650);
WIRE 16 -1 (-3500 3525)(-3500 3125);
WIRE 16 -1 (-3100 2825)(-3100 2925);
WIRE 16 -1 (-5025 2825)(-5025 3225);
WIRE 16 -1 (-2700 2825)(-2700 2925);
WIRE 16 -1 (-3025 2225)(-3025 1825);
FORCENOTE
PCIE_UPLINK POP: C6B4, C6B6, C6B9, C6B11, C6B14, C6B15, C6B17, C6B19, C6B5, C6B8, C6B10, C6B12, C6B13, C6B16, C6B18, C6B20,
(-7450 4525) 0;
DISPLAY LEFT (-7450 4525);
DISPLAY 1.021277 (-7450 4525);
PAINT PURPLE (-7450 4525);
FORCENOTE
TP FAB1 ADD PE1[8:15] PATH TO X24  SLOT
(-4675 925) 0;
DISPLAY LEFT (-4675 925);
DISPLAY 1.702128 (-4675 925);
PAINT RED (-4675 925);
FORCENOTE
C3M2, C3M11, C3M13, C3M3, C3M25, C3M28, C3M36, C3M34, C3M1, C3M12, C3M14, C3M4, C3M26, C3M32, C3M35 AND C3M33
(-7450 4450) 0;
DISPLAY LEFT (-7450 4450);
DISPLAY 1.021277 (-7450 4450);
PAINT PURPLE (-7450 4450);
QUIT
